G04 ================== begin FILE IDENTIFICATION RECORD ==================*
G04 Layout Name:  9324_DA0F0TMBIJ0_F0T_Motherboard_J_v01_20230324_0910.brd*
G04 Film Name:    ssb*
G04 File Format:  Gerber RS274X*
G04 File Origin:  Cadence Allegro 17.2-S081*
G04 Origin Date:  Sat Mar 25 08:45:17 2023*
G04 *
G04 Layer:  DRAWING FORMAT/TITLE_BLOCK_A*
G04 Layer:  BOARD GEOMETRY/DESIGN_OUTLINE*
G04 Layer:  BOARD GEOMETRY/CUTOUT*
G04 Layer:  DRAWING FORMAT/TITLE_BLOCK*
G04 Layer:  MANUFACTURING/TP_TEXT_BOTTOM*
G04 Layer:  REF DES/SILKSCREEN_BOTTOM*
G04 Layer:  PACKAGE GEOMETRY/SILKSCREEN_BOTTOM*
G04 Layer:  MANUFACTURING/PHOTOPLOT_OUTLINE*
G04 Layer:  DRAWING FORMAT/TITLE_DATA_SSB*
G04 Layer:  BOARD GEOMETRY/SILKSCREEN_BOTTOM*
G04 *
G04 Offset:    (0.00 0.00)*
G04 Mirror:    No*
G04 Mode:      Positive*
G04 Rotation:  0*
G04 FullContactRelief:  No*
G04 UndefLineWidth:     6.00*
G04 ================== end FILE IDENTIFICATION RECORD ====================*
%FSLAX25Y25*MOIN*%
%IR0*IPPOS*OFA0.00000B0.00000*MIA0B0*SFA1.00000B1.00000*%
%ADD10C,.006*%
G75*
%LPD*%
G75*
G36*
G01X49239Y436624D02*
X52452Y435554D01*
X50310Y433412D01*
X49239Y436624D01*
G37*
G36*
G01D02*
X52452Y435554D01*
X50310Y433412D01*
X49239Y436624D01*
G37*
G36*
G01X59984Y764310D02*
Y761870D01*
X57544Y763090D01*
X59984Y764310D01*
G37*
G36*
G01D02*
Y761870D01*
X57544Y763090D01*
X59984Y764310D01*
G37*
G36*
G01X172685Y1346640D02*
Y1343258D01*
X154369D01*
Y1346640D01*
X172685D01*
G37*
G36*
G01X211085D02*
Y1343258D01*
X192769D01*
Y1346640D01*
X211085D01*
G37*
G36*
G01X343270Y720307D02*
X346034Y718925D01*
X343270Y717543D01*
Y720307D01*
G37*
G36*
G01D02*
X346034Y718925D01*
X343270Y717543D01*
Y720307D01*
G37*
G36*
G01X507928Y92964D02*
X506867Y96146D01*
X510049Y95086D01*
X507928Y92964D01*
G37*
G36*
G01D02*
X506867Y96146D01*
X510049Y95086D01*
X507928Y92964D01*
G37*
G36*
G01X552274Y117350D02*
X549060Y118421D01*
X551202Y120563D01*
X552274Y117350D01*
G37*
G36*
G01D02*
X549060Y118421D01*
X551202Y120563D01*
X552274Y117350D01*
G37*
G36*
G01X686265Y1346665D02*
Y1343283D01*
X667949D01*
Y1346665D01*
X686265D01*
G37*
G36*
G01X725162D02*
Y1343283D01*
X706846D01*
Y1346665D01*
X725162D01*
G37*
G36*
G01X791477Y311408D02*
X793657Y312700D01*
Y310240D01*
X791477Y311408D01*
G37*
G36*
G01D02*
X793657Y312700D01*
Y310240D01*
X791477Y311408D01*
G37*
G36*
G01X783694Y762538D02*
X781514Y763706D01*
X783694Y764998D01*
Y762538D01*
G37*
G36*
G01D02*
X781514Y763706D01*
X783694Y764998D01*
Y762538D01*
G37*
G36*
G01X798575Y285478D02*
X796395Y286646D01*
X798575Y287938D01*
Y285478D01*
G37*
G36*
G01D02*
X796395Y286646D01*
X798575Y287938D01*
Y285478D01*
G37*
G36*
G01X819000Y271448D02*
X816820Y270156D01*
Y272616D01*
X819000Y271448D01*
G37*
G36*
G01D02*
X816820Y270156D01*
Y272616D01*
X819000Y271448D01*
G37*
G36*
G01X818978Y766809D02*
X817478Y769809D01*
X820478D01*
X818978Y766809D01*
G37*
G36*
G01D02*
X817478Y769809D01*
X820478D01*
X818978Y766809D01*
G37*
G36*
G01X841179Y310520D02*
X838999Y311688D01*
X841179Y312980D01*
Y310520D01*
G37*
G36*
G01D02*
X838999Y311688D01*
X841179Y312980D01*
Y310520D01*
G37*
G36*
G01X844397Y765074D02*
X845630Y765690D01*
Y764458D01*
X844397Y765074D01*
G37*
G36*
G01D02*
X845630Y765690D01*
Y764458D01*
X844397Y765074D01*
G37*
G36*
G01X865877Y770225D02*
Y768225D01*
X862877Y769225D01*
X865877Y770225D01*
G37*
G36*
G01D02*
Y768225D01*
X862877Y769225D01*
X865877Y770225D01*
G37*
G36*
G01X1145957Y1383870D02*
Y1380488D01*
X1127641D01*
Y1383870D01*
X1145957D01*
G37*
G36*
G01X1162435Y583686D02*
X1164435Y587686D01*
X1166435Y583686D01*
X1162435D01*
G37*
G36*
G01D02*
X1164435Y587686D01*
X1166435Y583686D01*
X1162435D01*
G37*
G36*
G01X1184854Y1383870D02*
Y1380488D01*
X1166538D01*
Y1383870D01*
X1184854D01*
G37*
G36*
G01X1435979Y729672D02*
X1434597Y726908D01*
X1433215Y729672D01*
X1435979D01*
G37*
G36*
G01D02*
X1434597Y726908D01*
X1433215Y729672D01*
X1435979D01*
G37*
G36*
G01X1465848Y745705D02*
X1467865Y744332D01*
X1465484Y743001D01*
X1465848Y745705D01*
G37*
G36*
G01D02*
X1467865Y744332D01*
X1465484Y743001D01*
X1465848Y745705D01*
G37*
G36*
G01X1713257Y180110D02*
X1716021D01*
X1714639Y182874D01*
X1713257Y180110D01*
G37*
G36*
G01X1879155Y357947D02*
X1876155Y363947D01*
X1882155D01*
X1879155Y357947D01*
G37*
G36*
G01Y605847D02*
X1876155Y611847D01*
X1882155D01*
X1879155Y605847D01*
G37*
G36*
G01X1897275Y-343D02*
X1903275D01*
X1900275Y-6343D01*
X1897275Y-343D01*
G37*
G36*
G01D02*
X1903275D01*
X1900275Y-6343D01*
X1897275Y-343D01*
G37*
G36*
G01X1889155Y455899D02*
X1892155Y449899D01*
X1886155D01*
X1889155Y455899D01*
G37*
G36*
G01Y703799D02*
X1892155Y697799D01*
X1886155D01*
X1889155Y703799D01*
G37*
G36*
G01X1900275Y729807D02*
X1897275Y735807D01*
X1903275D01*
X1900275Y729807D01*
G37*
G36*
G01X1913605Y571209D02*
X1907605D01*
X1910605Y577209D01*
X1913605Y571209D01*
G37*
G36*
G01D02*
X1907605D01*
X1910605Y577209D01*
X1913605Y571209D01*
G37*
G36*
G01X1910275Y827759D02*
X1913275Y821759D01*
X1907275D01*
X1910275Y827759D01*
G37*
G36*
G01X1917732Y613856D02*
X1923732D01*
X1920732Y607856D01*
X1917732Y613856D01*
G37*
G36*
G01D02*
X1923732D01*
X1920732Y607856D01*
X1917732Y613856D01*
G37*
G36*
G01X1934644Y1183832D02*
X1928644D01*
X1931644Y1189832D01*
X1934644Y1183832D01*
G37*
G36*
G01D02*
X1928644D01*
X1931644Y1189832D01*
X1934644Y1183832D01*
G37*
G36*
G01X1939395Y-153D02*
X1945395D01*
X1942395Y-6153D01*
X1939395Y-153D01*
G37*
G36*
G01D02*
X1945395D01*
X1942395Y-6153D01*
X1939395Y-153D01*
G37*
G36*
G01X1955885Y571309D02*
X1949885D01*
X1952885Y577309D01*
X1955885Y571309D01*
G37*
G36*
G01D02*
X1949885D01*
X1952885Y577309D01*
X1955885Y571309D01*
G37*
G36*
G01X1959699Y613998D02*
X1965699D01*
X1962699Y607998D01*
X1959699Y613998D01*
G37*
G36*
G01D02*
X1965699D01*
X1962699Y607998D01*
X1959699Y613998D01*
G37*
G36*
G01X1976528Y1183228D02*
X1970528D01*
X1973528Y1189228D01*
X1976528Y1183228D01*
G37*
G36*
G01D02*
X1970528D01*
X1973528Y1189228D01*
X1976528Y1183228D01*
G37*
G36*
G01X1981482Y-181D02*
X1987482D01*
X1984482Y-6181D01*
X1981482Y-181D01*
G37*
G36*
G01D02*
X1987482D01*
X1984482Y-6181D01*
X1981482Y-181D01*
G37*
G36*
G01X1997312Y571451D02*
X1991312D01*
X1994312Y577451D01*
X1997312Y571451D01*
G37*
G36*
G01D02*
X1991312D01*
X1994312Y577451D01*
X1997312Y571451D01*
G37*
G36*
G01X2001706Y614506D02*
X2007706D01*
X2004706Y608506D01*
X2001706Y614506D01*
G37*
G36*
G01D02*
X2007706D01*
X2004706Y608506D01*
X2001706Y614506D01*
G37*
G36*
G01X2018618Y1183403D02*
X2012618D01*
X2015618Y1189403D01*
X2018618Y1183403D01*
G37*
G36*
G01D02*
X2012618D01*
X2015618Y1189403D01*
X2018618Y1183403D01*
G37*
G36*
G01X2023452Y-1D02*
X2029452D01*
X2026452Y-6001D01*
X2023452Y-1D01*
G37*
G36*
G01D02*
X2029452D01*
X2026452Y-6001D01*
X2023452Y-1D01*
G37*
G36*
G01X2039202Y571801D02*
X2033202D01*
X2036202Y577801D01*
X2039202Y571801D01*
G37*
G36*
G01D02*
X2033202D01*
X2036202Y577801D01*
X2039202Y571801D01*
G37*
G36*
G01X2043590Y614067D02*
X2049590D01*
X2046590Y608067D01*
X2043590Y614067D01*
G37*
G36*
G01D02*
X2049590D01*
X2046590Y608067D01*
X2043590Y614067D01*
G37*
G36*
G01X2060419Y1184291D02*
X2054419D01*
X2057419Y1190291D01*
X2060419Y1184291D01*
G37*
G36*
G01D02*
X2054419D01*
X2057419Y1190291D01*
X2060419Y1184291D01*
G37*
G36*
G01X154369Y1342408D02*
Y1345790D01*
X172685D01*
Y1342408D01*
X154369D01*
G37*
G36*
G01X192769D02*
Y1345790D01*
X211085D01*
Y1342408D01*
X192769D01*
G37*
G36*
G01X254394Y676481D02*
Y694797D01*
X257776D01*
Y676481D01*
X254394D01*
G37*
G36*
G01X340595Y1277866D02*
Y1281248D01*
X358911D01*
Y1277866D01*
X340595D01*
G37*
G36*
G01D02*
Y1281248D01*
X358911D01*
Y1277866D01*
X340595D01*
G37*
G36*
G01X402222Y1266148D02*
Y1269530D01*
X420538D01*
Y1266148D01*
X402222D01*
G37*
G36*
G01D02*
Y1269530D01*
X420538D01*
Y1266148D01*
X402222D01*
G37*
G36*
G01X438393Y1266160D02*
Y1269542D01*
X456709D01*
Y1266160D01*
X438393D01*
G37*
G36*
G01D02*
Y1269542D01*
X456709D01*
Y1266160D01*
X438393D01*
G37*
G36*
G01X500864Y1277674D02*
Y1281056D01*
X519180D01*
Y1277674D01*
X500864D01*
G37*
G36*
G01D02*
Y1281056D01*
X519180D01*
Y1277674D01*
X500864D01*
G37*
G36*
G01X667949Y1342433D02*
Y1345815D01*
X686265D01*
Y1342433D01*
X667949D01*
G37*
G36*
G01X706846D02*
Y1345815D01*
X725162D01*
Y1342433D01*
X706846D01*
G37*
G36*
G01X1127641Y1377328D02*
Y1380710D01*
X1145957D01*
Y1377328D01*
X1127641D01*
G37*
G36*
G01D02*
Y1380710D01*
X1145957D01*
Y1377328D01*
X1127641D01*
G37*
G36*
G01Y1379637D02*
Y1383019D01*
X1145957D01*
Y1379637D01*
X1127641D01*
G37*
G36*
G01X1166538Y1377328D02*
Y1380710D01*
X1184854D01*
Y1377328D01*
X1166538D01*
G37*
G36*
G01D02*
Y1380710D01*
X1184854D01*
Y1377328D01*
X1166538D01*
G37*
G36*
G01Y1379637D02*
Y1383019D01*
X1184854D01*
Y1379637D01*
X1166538D01*
G37*
G36*
G01X1317136Y1278826D02*
Y1282208D01*
X1335452D01*
Y1278826D01*
X1317136D01*
G37*
G36*
G01D02*
Y1282208D01*
X1335452D01*
Y1278826D01*
X1317136D01*
G37*
G36*
G01D02*
Y1282208D01*
X1335452D01*
Y1278826D01*
X1317136D01*
G37*
G36*
G01D02*
Y1282208D01*
X1335452D01*
Y1278826D01*
X1317136D01*
G37*
G36*
G01D02*
Y1282208D01*
X1335452D01*
Y1278826D01*
X1317136D01*
G37*
G36*
G01D02*
Y1282208D01*
X1335452D01*
Y1278826D01*
X1317136D01*
G37*
G36*
G01X1378363Y1265648D02*
Y1269030D01*
X1396679D01*
Y1265648D01*
X1378363D01*
G37*
G36*
G01D02*
Y1269030D01*
X1396679D01*
Y1265648D01*
X1378363D01*
G37*
G36*
G01D02*
Y1269030D01*
X1396679D01*
Y1265648D01*
X1378363D01*
G37*
G36*
G01D02*
Y1269030D01*
X1396679D01*
Y1265648D01*
X1378363D01*
G37*
G36*
G01D02*
Y1269030D01*
X1396679D01*
Y1265648D01*
X1378363D01*
G37*
G36*
G01D02*
Y1269030D01*
X1396679D01*
Y1265648D01*
X1378363D01*
G37*
G36*
G01X1414534Y1265660D02*
Y1269042D01*
X1432850D01*
Y1265660D01*
X1414534D01*
G37*
G36*
G01D02*
Y1269042D01*
X1432850D01*
Y1265660D01*
X1414534D01*
G37*
G36*
G01D02*
Y1269042D01*
X1432850D01*
Y1265660D01*
X1414534D01*
G37*
G36*
G01D02*
Y1269042D01*
X1432850D01*
Y1265660D01*
X1414534D01*
G37*
G36*
G01D02*
Y1269042D01*
X1432850D01*
Y1265660D01*
X1414534D01*
G37*
G36*
G01D02*
Y1269042D01*
X1432850D01*
Y1265660D01*
X1414534D01*
G37*
G36*
G01X1477005Y1277674D02*
Y1281056D01*
X1495321D01*
Y1277674D01*
X1477005D01*
G37*
G36*
G01D02*
Y1281056D01*
X1495321D01*
Y1277674D01*
X1477005D01*
G37*
G36*
G01D02*
Y1281056D01*
X1495321D01*
Y1277674D01*
X1477005D01*
G37*
G36*
G01D02*
Y1281056D01*
X1495321D01*
Y1277674D01*
X1477005D01*
G37*
G36*
G01D02*
Y1281056D01*
X1495321D01*
Y1277674D01*
X1477005D01*
G37*
G36*
G01D02*
Y1281056D01*
X1495321D01*
Y1277674D01*
X1477005D01*
G37*
G36*
G01X1596497Y593785D02*
Y612101D01*
X1599879D01*
Y593785D01*
X1596497D01*
G37*
G36*
G01D02*
Y612101D01*
X1599879D01*
Y593785D01*
X1596497D01*
G37*
G36*
G01X1629115Y1376029D02*
Y1379411D01*
X1647431D01*
Y1376029D01*
X1629115D01*
G37*
G36*
G01D02*
Y1379411D01*
X1647431D01*
Y1376029D01*
X1629115D01*
G37*
G36*
G01D02*
Y1379411D01*
X1647431D01*
Y1376029D01*
X1629115D01*
G37*
G36*
G01D02*
Y1379411D01*
X1647431D01*
Y1376029D01*
X1629115D01*
G37*
G36*
G01D02*
Y1379411D01*
X1647431D01*
Y1376029D01*
X1629115D01*
G37*
G36*
G01D02*
Y1379411D01*
X1647431D01*
Y1376029D01*
X1629115D01*
G37*
G36*
G01X1668012D02*
Y1379411D01*
X1686328D01*
Y1376029D01*
X1668012D01*
G37*
G36*
G01D02*
Y1379411D01*
X1686328D01*
Y1376029D01*
X1668012D01*
G37*
G36*
G01D02*
Y1379411D01*
X1686328D01*
Y1376029D01*
X1668012D01*
G37*
G36*
G01D02*
Y1379411D01*
X1686328D01*
Y1376029D01*
X1668012D01*
G37*
G36*
G01D02*
Y1379411D01*
X1686328D01*
Y1376029D01*
X1668012D01*
G37*
G36*
G01D02*
Y1379411D01*
X1686328D01*
Y1376029D01*
X1668012D01*
G37*
G54D10*
G01X-6350Y-464479D02*
Y-539479D01*
X493650D01*
Y-464479D01*
X-6350D01*
G01X5650Y-529479D02*
Y-534479D01*
G01X4193Y-529479D02*
X7107D01*
G01X12017Y-534479D02*
X9483D01*
Y-529479D01*
X12017D01*
G01X11003Y-531896D02*
X9483D01*
G01X14583Y-529479D02*
Y-534479D01*
X17117D01*
G01X20950Y-534646D02*
X20823Y-534562D01*
Y-534396D01*
X20950Y-534312D01*
X21077Y-534396D01*
Y-534562D01*
X20950Y-534646D01*
G01Y-532396D02*
X20823Y-532312D01*
Y-532146D01*
X20950Y-532062D01*
X21077Y-532146D01*
Y-532312D01*
X20950Y-532396D01*
G01X25733Y-536146D02*
X25100Y-535312D01*
X24783Y-534479D01*
Y-531146D01*
X25100Y-530312D01*
X25733Y-529479D01*
G01X31150D02*
X30643Y-529646D01*
X30263Y-530062D01*
X30010Y-530562D01*
X29820Y-531229D01*
X29757Y-531979D01*
X29820Y-532729D01*
X30010Y-533396D01*
X30263Y-533896D01*
X30643Y-534312D01*
X31150Y-534479D01*
X31657Y-534312D01*
X32037Y-533896D01*
X32290Y-533396D01*
X32480Y-532729D01*
X32543Y-531979D01*
X32480Y-531229D01*
X32290Y-530562D01*
X32037Y-530062D01*
X31657Y-529646D01*
X31150Y-529479D01*
G01X34857Y-533479D02*
X35237Y-534062D01*
X35743Y-534396D01*
X36313Y-534479D01*
X36820Y-534396D01*
X37327Y-533979D01*
X37643Y-533479D01*
X37707Y-532979D01*
X37580Y-532396D01*
X37137Y-531979D01*
X36693Y-531812D01*
X36123D01*
G01X36693D02*
X37073Y-531562D01*
X37390Y-531146D01*
X37517Y-530646D01*
X37390Y-530146D01*
X37073Y-529729D01*
X36503Y-529479D01*
X35933Y-529562D01*
X35363Y-529896D01*
G01X41667Y-536146D02*
X42300Y-535312D01*
X42617Y-534479D01*
Y-531146D01*
X42300Y-530312D01*
X41667Y-529479D01*
G01X45057Y-533479D02*
X45437Y-534062D01*
X45943Y-534396D01*
X46513Y-534479D01*
X47020Y-534396D01*
X47527Y-533979D01*
X47843Y-533479D01*
X47907Y-532979D01*
X47780Y-532396D01*
X47337Y-531979D01*
X46893Y-531812D01*
X46323D01*
G01X46893D02*
X47273Y-531562D01*
X47590Y-531146D01*
X47717Y-530646D01*
X47590Y-530146D01*
X47273Y-529729D01*
X46703Y-529479D01*
X46133Y-529562D01*
X45563Y-529896D01*
G01X50347Y-530312D02*
X50727Y-529812D01*
X51170Y-529562D01*
X51677Y-529479D01*
X52310Y-529646D01*
X52753Y-530062D01*
X52880Y-530562D01*
X52817Y-531062D01*
X52563Y-531479D01*
X51297Y-532312D01*
X50727Y-532896D01*
X50347Y-533729D01*
X50220Y-534479D01*
X52880D01*
G01X56523D02*
X56650Y-533396D01*
X56840Y-532479D01*
X57093Y-531646D01*
X57410Y-530729D01*
X57917Y-529479D01*
X55383D01*
G01X60927Y-532812D02*
X62573D01*
G01X65647Y-530312D02*
X66027Y-529812D01*
X66470Y-529562D01*
X66977Y-529479D01*
X67610Y-529646D01*
X68053Y-530062D01*
X68180Y-530562D01*
X68117Y-531062D01*
X67863Y-531479D01*
X66597Y-532312D01*
X66027Y-532896D01*
X65647Y-533729D01*
X65520Y-534479D01*
X68180D01*
G01X70557Y-533479D02*
X70937Y-534062D01*
X71443Y-534396D01*
X72013Y-534479D01*
X72520Y-534396D01*
X73027Y-533979D01*
X73343Y-533479D01*
X73407Y-532979D01*
X73280Y-532396D01*
X72837Y-531979D01*
X72393Y-531812D01*
X71823D01*
G01X72393D02*
X72773Y-531562D01*
X73090Y-531146D01*
X73217Y-530646D01*
X73090Y-530146D01*
X72773Y-529729D01*
X72203Y-529479D01*
X71633Y-529562D01*
X71063Y-529896D01*
G01X77810Y-534479D02*
Y-529479D01*
X75467Y-533062D01*
X78633D01*
G01X80757Y-533729D02*
X81137Y-534146D01*
X81580Y-534396D01*
X82150Y-534479D01*
X82720Y-534312D01*
X83163Y-533979D01*
X83480Y-533396D01*
X83543Y-532729D01*
X83417Y-532062D01*
X83100Y-531646D01*
X82657Y-531312D01*
X82213Y-531229D01*
X81770Y-531312D01*
X81200Y-531646D01*
X81390Y-529479D01*
X83100D01*
G01X91147Y-534479D02*
Y-529479D01*
X93553D01*
G01X92667Y-531896D02*
X91147D01*
G01X95867Y-534479D02*
X97450Y-529479D01*
X99033Y-534479D01*
G01X98463Y-532729D02*
X96437D01*
G01X101220Y-534479D02*
X103880Y-529479D01*
G01X101220D02*
X103880Y-534479D01*
G01X107650Y-534646D02*
X107523Y-534562D01*
Y-534396D01*
X107650Y-534312D01*
X107777Y-534396D01*
Y-534562D01*
X107650Y-534646D01*
G01Y-532396D02*
X107523Y-532312D01*
Y-532146D01*
X107650Y-532062D01*
X107777Y-532146D01*
Y-532312D01*
X107650Y-532396D01*
G01X112433Y-536146D02*
X111800Y-535312D01*
X111483Y-534479D01*
Y-531146D01*
X111800Y-530312D01*
X112433Y-529479D01*
G01X117850D02*
X117343Y-529646D01*
X116963Y-530062D01*
X116710Y-530562D01*
X116520Y-531229D01*
X116457Y-531979D01*
X116520Y-532729D01*
X116710Y-533396D01*
X116963Y-533896D01*
X117343Y-534312D01*
X117850Y-534479D01*
X118357Y-534312D01*
X118737Y-533896D01*
X118990Y-533396D01*
X119180Y-532729D01*
X119243Y-531979D01*
X119180Y-531229D01*
X118990Y-530562D01*
X118737Y-530062D01*
X118357Y-529646D01*
X117850Y-529479D01*
G01X121557Y-533479D02*
X121937Y-534062D01*
X122443Y-534396D01*
X123013Y-534479D01*
X123520Y-534396D01*
X124027Y-533979D01*
X124343Y-533479D01*
X124407Y-532979D01*
X124280Y-532396D01*
X123837Y-531979D01*
X123393Y-531812D01*
X122823D01*
G01X123393D02*
X123773Y-531562D01*
X124090Y-531146D01*
X124217Y-530646D01*
X124090Y-530146D01*
X123773Y-529729D01*
X123203Y-529479D01*
X122633Y-529562D01*
X122063Y-529896D01*
G01X128367Y-536146D02*
X129000Y-535312D01*
X129317Y-534479D01*
Y-531146D01*
X129000Y-530312D01*
X128367Y-529479D01*
G01X131757Y-533479D02*
X132137Y-534062D01*
X132643Y-534396D01*
X133213Y-534479D01*
X133720Y-534396D01*
X134227Y-533979D01*
X134543Y-533479D01*
X134607Y-532979D01*
X134480Y-532396D01*
X134037Y-531979D01*
X133593Y-531812D01*
X133023D01*
G01X133593D02*
X133973Y-531562D01*
X134290Y-531146D01*
X134417Y-530646D01*
X134290Y-530146D01*
X133973Y-529729D01*
X133403Y-529479D01*
X132833Y-529562D01*
X132263Y-529896D01*
G01X137173Y-533896D02*
X137617Y-534312D01*
X138123Y-534479D01*
X138630Y-534312D01*
X139073Y-533812D01*
X139390Y-533062D01*
X139517Y-532312D01*
Y-531396D01*
X139390Y-530646D01*
X139073Y-529979D01*
X138693Y-529646D01*
X138250Y-529479D01*
X137743Y-529646D01*
X137363Y-529979D01*
X137110Y-530479D01*
X136983Y-531146D01*
X137110Y-531729D01*
X137427Y-532312D01*
X137807Y-532646D01*
X138250Y-532729D01*
X138757Y-532562D01*
X139137Y-532146D01*
X139517Y-531396D01*
G01X143223Y-534479D02*
X143350Y-533396D01*
X143540Y-532479D01*
X143793Y-531646D01*
X144110Y-530729D01*
X144617Y-529479D01*
X142083D01*
G01X147627Y-532812D02*
X149273D01*
G01X152157Y-533479D02*
X152537Y-534062D01*
X153043Y-534396D01*
X153613Y-534479D01*
X154120Y-534396D01*
X154627Y-533979D01*
X154943Y-533479D01*
X155007Y-532979D01*
X154880Y-532396D01*
X154437Y-531979D01*
X153993Y-531812D01*
X153423D01*
G01X153993D02*
X154373Y-531562D01*
X154690Y-531146D01*
X154817Y-530646D01*
X154690Y-530146D01*
X154373Y-529729D01*
X153803Y-529479D01*
X153233Y-529562D01*
X152663Y-529896D01*
G01X157447Y-532396D02*
X157890Y-531812D01*
X158270Y-531479D01*
X158777Y-531312D01*
X159220Y-531479D01*
X159537Y-531812D01*
X159790Y-532312D01*
X159853Y-532896D01*
X159790Y-533396D01*
X159537Y-533896D01*
X159157Y-534312D01*
X158713Y-534479D01*
X158207Y-534312D01*
X157763Y-533812D01*
X157510Y-533062D01*
X157447Y-532229D01*
X157573Y-531146D01*
X157763Y-530562D01*
X158080Y-529979D01*
X158523Y-529562D01*
X158967Y-529479D01*
X159410Y-529646D01*
X159727Y-530062D01*
G01X163750Y-534479D02*
Y-529479D01*
X162990Y-530479D01*
G01Y-534479D02*
X164510D01*
G01X169610D02*
Y-529479D01*
X167267Y-533062D01*
X170433D01*
G01X51583Y1969D02*
G03X53551Y0I1968J-1D01*
G01X319693D01*
G03X321661Y1969I0J1968D01*
G01Y38504D01*
G02X329535Y46378I7874J0D01*
G01X488591D01*
G02X496465Y38504I0J-7874D01*
G01Y22756D01*
G03X498433Y20787I1968J-1D01*
G01X764575D01*
G03X766543Y22756I0J1968D01*
G01Y38504D01*
G02X774417Y46378I7874J0D01*
G01X871260D01*
G03X879134Y54252I0J7874D01*
G01Y131004D01*
G02X887008Y138878I7874J0D01*
G01X1011024D01*
G02X1018898Y131004I0J-7874D01*
G01Y54252D01*
G03X1026772Y46378I7874J0D01*
G01X1518118D01*
G02X1525992Y38504I0J-7874D01*
G01Y1969D01*
G03X1527961Y0I1969J0D01*
G01X1794102D01*
G03X1796071Y1969I0J1969D01*
G01Y38504D01*
G02X1803945Y46378I7874J0D01*
G01X1849606D01*
G03X1857480Y54252I0J7874D01*
G01Y305794D01*
G03X1855174Y311361I-7873J0D01*
G01X1846007Y320528D01*
G02X1843701Y326096I5568J5568D01*
G01Y1593983D01*
G03X1841395Y1599550I-7873J0D01*
G01X1834196Y1606749D01*
G02X1831890Y1612317I5568J5568D01*
G01Y1732244D01*
G03X1824016Y1740118I-7874J0D01*
G01X1091777D01*
G03X1089809Y1738150I0J-1968D01*
G01Y1736654D01*
G02X1087854Y1734921I-1955J236D01*
G01X769705D01*
G02X767750Y1736654I0J1969D01*
G01Y1738150D01*
G03X765782Y1740118I-1968J0D01*
G01X33465D01*
G03X25591Y1732244I0J-7874D01*
G01Y1612317D01*
G02X23284Y1606749I-7875J1D01*
G01X10180Y1593645D01*
G03X7874Y1588077I5568J-5568D01*
G01Y320191D01*
G02X5568Y314623I-7874J0D01*
G01X2306Y311361D01*
G03X0Y305794I5567J-5567D01*
G01Y54252D01*
G03X7874Y46378I7874J0D01*
G01X43709D01*
G02X51583Y38504I0J-7874D01*
G01Y1969D01*
G01X16535Y87795D02*
G02X38583I11024J0D01*
G02X16535I-11024J0D01*
G01X18661Y1420331D02*
G02X58031I19685J0D01*
G02X18661I-19685J0D01*
G01X29685Y631890D02*
G02X51732I11023J0D01*
G02X29685I-11024J0D01*
G01Y1368898D02*
G02X51732I11023J0D01*
G02X29685I-11024J0D01*
G01X62205Y1714961D02*
G02X40157I-11024J0D01*
G02X62205I11024J0D01*
G01X52141Y119148D02*
X56741Y123451D01*
G02X65079Y114538I4169J-4456D01*
G01X60479Y110235D01*
G02X52141Y119148I-4169J4456D01*
G01X98248Y605378D02*
G02X137618I19685J0D01*
G02X98248I-19685J0D01*
G01X197098Y294335D02*
Y260083D01*
G02X157728I-19685J0D01*
G01Y294335D01*
G02X197098I19685J0D01*
G01X196996Y1671142D02*
Y1644764D01*
G02X157626I-19685J0D01*
G01Y1671142D01*
G02X196996I19685J0D01*
G01X188650Y-464479D02*
Y-539479D01*
G01Y-514479D02*
X291650D01*
Y-489479D01*
G01X188650D02*
X291650D01*
G01X247177Y191535D02*
X253476D01*
G02Y178937I0J-6299D01*
G01X247177D01*
G02Y191535I0J6299D01*
G01X269618Y185236D02*
G02X284579I7481J0D01*
G02X269618I-7481J0D01*
G01X291650Y-464479D02*
Y-539479D01*
G01X293650Y-464479D02*
Y-539479D01*
G01X299157Y-524479D02*
Y-519479D01*
X300423D01*
X300930Y-519729D01*
X301310Y-520062D01*
X301627Y-520562D01*
X301880Y-521146D01*
X301943Y-521979D01*
X301880Y-522812D01*
X301627Y-523396D01*
X301310Y-523896D01*
X300930Y-524229D01*
X300423Y-524479D01*
X299157D01*
G01X304067D02*
X305650Y-519479D01*
X307233Y-524479D01*
G01X306663Y-522729D02*
X304637D01*
G01X310750Y-519479D02*
Y-524479D01*
G01X309293Y-519479D02*
X312207D01*
G01X317117Y-524479D02*
X314583D01*
Y-519479D01*
X317117D01*
G01X316103Y-521896D02*
X314583D01*
G01X320950Y-524646D02*
X320823Y-524562D01*
Y-524396D01*
X320950Y-524312D01*
X321077Y-524396D01*
Y-524562D01*
X320950Y-524646D01*
G01Y-522396D02*
X320823Y-522312D01*
Y-522146D01*
X320950Y-522062D01*
X321077Y-522146D01*
Y-522312D01*
X320950Y-522396D01*
G01X299283Y-499479D02*
Y-494479D01*
X300803D01*
X301310Y-494729D01*
X301690Y-495312D01*
X301817Y-495979D01*
X301690Y-496646D01*
X301373Y-497146D01*
X300803Y-497396D01*
X299283D01*
G01X304510Y-499646D02*
X306790Y-494479D01*
G01X309293Y-499479D02*
Y-494479D01*
X312207Y-499479D01*
Y-494479D01*
G01X315850Y-499646D02*
X315723Y-499562D01*
Y-499396D01*
X315850Y-499312D01*
X315977Y-499396D01*
Y-499562D01*
X315850Y-499646D01*
G01Y-497396D02*
X315723Y-497312D01*
Y-497146D01*
X315850Y-497062D01*
X315977Y-497146D01*
Y-497312D01*
X315850Y-497396D01*
G01X293650Y-514479D02*
X493650D01*
G01X293650Y-489479D02*
X493650D01*
G01X299283Y-474479D02*
Y-469479D01*
X300803D01*
X301310Y-469729D01*
X301690Y-470312D01*
X301817Y-470979D01*
X301690Y-471646D01*
X301373Y-472146D01*
X300803Y-472396D01*
X299283D01*
G01X304383Y-474479D02*
Y-469479D01*
X305967D01*
X306473Y-469729D01*
X306790Y-470062D01*
X306917Y-470729D01*
X306790Y-471396D01*
X306410Y-471812D01*
X305967Y-472062D01*
X304383D01*
G01X305967D02*
X306917Y-474479D01*
G01X310750D02*
X310243Y-474396D01*
X309800Y-474062D01*
X309420Y-473562D01*
X309167Y-472979D01*
X309040Y-472312D01*
Y-471646D01*
X309167Y-470979D01*
X309420Y-470396D01*
X309800Y-469896D01*
X310243Y-469562D01*
X310750Y-469479D01*
X311257Y-469562D01*
X311700Y-469896D01*
X312080Y-470396D01*
X312333Y-470979D01*
X312460Y-471646D01*
Y-472312D01*
X312333Y-472979D01*
X312080Y-473562D01*
X311700Y-474062D01*
X311257Y-474396D01*
X310750Y-474479D01*
G01X314583Y-473479D02*
X314900Y-473979D01*
X315280Y-474312D01*
X315723Y-474479D01*
X316230Y-474312D01*
X316610Y-473979D01*
X316990Y-473479D01*
X317117Y-472812D01*
Y-469479D01*
G01X322217Y-474479D02*
X319683D01*
Y-469479D01*
X322217D01*
G01X321203Y-471896D02*
X319683D01*
G01X327443Y-469896D02*
X327063Y-469646D01*
X326620Y-469479D01*
X326113D01*
X325543Y-469729D01*
X325100Y-470146D01*
X324783Y-470646D01*
X324530Y-471479D01*
X324467Y-472229D01*
X324593Y-472979D01*
X324783Y-473479D01*
X325163Y-473979D01*
X325607Y-474312D01*
X326050Y-474479D01*
X326493D01*
X326937Y-474312D01*
X327317Y-474062D01*
X327633Y-473729D01*
G01X331150Y-469479D02*
Y-474479D01*
G01X329693Y-469479D02*
X332607D01*
G01X336250Y-474646D02*
X336123Y-474562D01*
Y-474396D01*
X336250Y-474312D01*
X336377Y-474396D01*
Y-474562D01*
X336250Y-474646D01*
G01Y-472396D02*
X336123Y-472312D01*
Y-472146D01*
X336250Y-472062D01*
X336377Y-472146D01*
Y-472312D01*
X336250Y-472396D01*
G01X300019Y991220D02*
G02X313523I6752J0D01*
G02X300019I-6752J0D01*
G01X316200Y1391831D02*
G02X328799I6299J0D01*
G02X316200I-6299J0D01*
G01X343346Y811122D02*
G02X356850I6752J0D01*
G02X343346I-6752J0D01*
G01X349310Y1171319D02*
G02X362814I6752J0D01*
G02X349310I-6752J0D01*
G01X362598Y87795D02*
G02X384646I11024J0D01*
G02X362598I-11024J0D01*
G01X365287Y191535D02*
X371587D01*
G02Y178937I0J-6299D01*
G01X365287D01*
G02Y191535I0J6299D01*
G01X384647Y1714961D02*
G02X406694I11023J0D01*
G02X384647I-11023J0D01*
G01X387728Y185236D02*
G02X402689I7481J0D01*
G02X387728I-7480J0D01*
G01X408650Y-514479D02*
Y-539479D01*
G01X411283Y-516979D02*
Y-521979D01*
X413817D01*
G01X416890Y-516979D02*
X418410D01*
G01X417650D02*
Y-521979D01*
G01X416890D02*
X418410D01*
G01X423257Y-519312D02*
X423510Y-519062D01*
X423700Y-518646D01*
X423827Y-518062D01*
X423700Y-517562D01*
X423447Y-517229D01*
X423003Y-516979D01*
X421293D01*
Y-521979D01*
X423383D01*
X423827Y-521646D01*
X424080Y-521146D01*
X424207Y-520562D01*
X424080Y-519979D01*
X423700Y-519479D01*
X423257Y-519312D01*
X421293D01*
G01X427850Y-522146D02*
X427723Y-522062D01*
Y-521896D01*
X427850Y-521812D01*
X427977Y-521896D01*
Y-522062D01*
X427850Y-522146D01*
G01Y-519896D02*
X427723Y-519812D01*
Y-519646D01*
X427850Y-519562D01*
X427977Y-519646D01*
Y-519812D01*
X427850Y-519896D01*
G01X447283Y1698268D02*
G02X434803I-6240J0D01*
G02X447283I6240J0D01*
G01X451650Y-514479D02*
Y-539479D01*
G01Y-489479D02*
Y-514479D01*
G01X456663Y-541646D02*
X456770Y-541521D01*
X456850Y-541312D01*
X456903Y-541021D01*
X456850Y-540771D01*
X456743Y-540604D01*
X456557Y-540479D01*
X455837D01*
Y-542979D01*
X456717D01*
X456903Y-542812D01*
X457010Y-542562D01*
X457063Y-542271D01*
X457010Y-541979D01*
X456850Y-541729D01*
X456663Y-541646D01*
X455837D01*
G01X459130Y-542979D02*
Y-541312D01*
G01Y-541604D02*
X459023Y-541437D01*
X458863Y-541354D01*
X458677Y-541312D01*
X458490Y-541396D01*
X458330Y-541562D01*
X458223Y-541812D01*
X458170Y-542146D01*
X458223Y-542479D01*
X458330Y-542729D01*
X458490Y-542896D01*
X458677Y-542979D01*
X458863Y-542937D01*
X459023Y-542812D01*
X459130Y-542646D01*
G01X460450Y-542687D02*
X460583Y-542854D01*
X460770Y-542979D01*
X460930D01*
X461090Y-542896D01*
X461197Y-542771D01*
X461250Y-542604D01*
X461223Y-542354D01*
X461117Y-542229D01*
X460637Y-541979D01*
X460530Y-541687D01*
X460583Y-541479D01*
X460690Y-541354D01*
X460850Y-541312D01*
X461010Y-541354D01*
X461170Y-541479D01*
G01X462650Y-541854D02*
X463503D01*
X463423Y-541562D01*
X463290Y-541396D01*
X463103Y-541312D01*
X462917Y-541354D01*
X462757Y-541479D01*
X462650Y-541771D01*
X462597Y-542021D01*
Y-542271D01*
X462650Y-542521D01*
X462783Y-542771D01*
X462943Y-542937D01*
X463130Y-542979D01*
X463317Y-542896D01*
X463503Y-542646D01*
G01X464770Y-542979D02*
Y-540479D01*
G01Y-541729D02*
X464903Y-541479D01*
X465063Y-541354D01*
X465223Y-541312D01*
X465463Y-541396D01*
X465623Y-541562D01*
X465730Y-541854D01*
Y-542187D01*
X465677Y-542521D01*
X465570Y-542771D01*
X465383Y-542937D01*
X465223Y-542979D01*
X465063Y-542937D01*
X464903Y-542812D01*
X464770Y-542604D01*
G01X467450Y-542979D02*
X467290Y-542937D01*
X467130Y-542771D01*
X467023Y-542479D01*
X466970Y-542146D01*
X467023Y-541812D01*
X467130Y-541521D01*
X467290Y-541354D01*
X467450Y-541312D01*
X467610Y-541354D01*
X467770Y-541521D01*
X467877Y-541812D01*
X467903Y-542146D01*
X467877Y-542479D01*
X467770Y-542771D01*
X467610Y-542937D01*
X467450Y-542979D01*
G01X470130D02*
Y-541312D01*
G01Y-541604D02*
X470023Y-541437D01*
X469863Y-541354D01*
X469677Y-541312D01*
X469490Y-541396D01*
X469330Y-541562D01*
X469223Y-541812D01*
X469170Y-542146D01*
X469223Y-542479D01*
X469330Y-542729D01*
X469490Y-542896D01*
X469677Y-542979D01*
X469863Y-542937D01*
X470023Y-542812D01*
X470130Y-542646D01*
G01X471477Y-542979D02*
Y-541312D01*
G01Y-541646D02*
X471610Y-541479D01*
X471743Y-541354D01*
X471930Y-541312D01*
X472063Y-541354D01*
X472223Y-541479D01*
G01X474530Y-540479D02*
Y-542979D01*
G01Y-542604D02*
X474423Y-542812D01*
X474263Y-542937D01*
X474077Y-542979D01*
X473863Y-542896D01*
X473703Y-542687D01*
X473597Y-542437D01*
X473570Y-542146D01*
X473597Y-541854D01*
X473703Y-541604D01*
X473863Y-541396D01*
X474077Y-541312D01*
X474263Y-541354D01*
X474397Y-541437D01*
X474530Y-541604D01*
G01X477917Y-542979D02*
Y-540479D01*
X478583D01*
X478797Y-540604D01*
X478930Y-540771D01*
X478983Y-541104D01*
X478930Y-541437D01*
X478770Y-541646D01*
X478583Y-541771D01*
X477917D01*
G01X478583D02*
X478983Y-542979D01*
G01X480250Y-541854D02*
X481103D01*
X481023Y-541562D01*
X480890Y-541396D01*
X480703Y-541312D01*
X480517Y-541354D01*
X480357Y-541479D01*
X480250Y-541771D01*
X480197Y-542021D01*
Y-542271D01*
X480250Y-542521D01*
X480383Y-542771D01*
X480543Y-542937D01*
X480730Y-542979D01*
X480917Y-542896D01*
X481103Y-542646D01*
G01X482370Y-541312D02*
X482850Y-542979D01*
X483330Y-541312D01*
G01X485050Y-543062D02*
X484997Y-543021D01*
Y-542937D01*
X485050Y-542896D01*
X485103Y-542937D01*
Y-543021D01*
X485050Y-543062D01*
G01X487250Y-542979D02*
X487437Y-542937D01*
X487650Y-542812D01*
X487783Y-542604D01*
X487837Y-542312D01*
X487783Y-542021D01*
X487623Y-541771D01*
X487383Y-541646D01*
X487117D01*
X486957Y-541562D01*
X486823Y-541354D01*
X486770Y-541062D01*
X486850Y-540771D01*
X487037Y-540562D01*
X487250Y-540479D01*
X487463Y-540562D01*
X487650Y-540771D01*
X487730Y-541062D01*
X487677Y-541354D01*
X487543Y-541562D01*
X487383Y-541646D01*
X487117D01*
X486877Y-541771D01*
X486717Y-542021D01*
X486663Y-542312D01*
X486717Y-542604D01*
X486850Y-542812D01*
X487063Y-542937D01*
X487250Y-542979D01*
G01X489663Y-541646D02*
X489770Y-541521D01*
X489850Y-541312D01*
X489903Y-541021D01*
X489850Y-540771D01*
X489743Y-540604D01*
X489557Y-540479D01*
X488837D01*
Y-542979D01*
X489717D01*
X489903Y-542812D01*
X490010Y-542562D01*
X490063Y-542271D01*
X490010Y-541979D01*
X489850Y-541729D01*
X489663Y-541646D01*
X488837D01*
G01X455550Y-516979D02*
Y-521979D01*
G01X454093Y-516979D02*
X457007D01*
G01X460650Y-521979D02*
X460270Y-521896D01*
X459890Y-521562D01*
X459637Y-520979D01*
X459510Y-520312D01*
X459637Y-519646D01*
X459890Y-519062D01*
X460270Y-518729D01*
X460650Y-518646D01*
X461030Y-518729D01*
X461410Y-519062D01*
X461663Y-519646D01*
X461727Y-520312D01*
X461663Y-520979D01*
X461410Y-521562D01*
X461030Y-521896D01*
X460650Y-521979D01*
G01X465750D02*
X465370Y-521896D01*
X464990Y-521562D01*
X464737Y-520979D01*
X464610Y-520312D01*
X464737Y-519646D01*
X464990Y-519062D01*
X465370Y-518729D01*
X465750Y-518646D01*
X466130Y-518729D01*
X466510Y-519062D01*
X466763Y-519646D01*
X466827Y-520312D01*
X466763Y-520979D01*
X466510Y-521562D01*
X466130Y-521896D01*
X465750Y-521979D01*
G01X470850D02*
Y-516979D01*
G01X475950Y-522146D02*
X475823Y-522062D01*
Y-521896D01*
X475950Y-521812D01*
X476077Y-521896D01*
Y-522062D01*
X475950Y-522146D01*
G01Y-519896D02*
X475823Y-519812D01*
Y-519646D01*
X475950Y-519562D01*
X476077Y-519646D01*
Y-519812D01*
X475950Y-519896D01*
G01X454283Y-496979D02*
Y-491979D01*
X455867D01*
X456373Y-492229D01*
X456690Y-492562D01*
X456817Y-493229D01*
X456690Y-493896D01*
X456310Y-494312D01*
X455867Y-494562D01*
X454283D01*
G01X455867D02*
X456817Y-496979D01*
G01X461917D02*
X459383D01*
Y-491979D01*
X461917D01*
G01X460903Y-494396D02*
X459383D01*
G01X464167Y-491979D02*
X465750Y-496979D01*
X467333Y-491979D01*
G01X470850Y-497146D02*
X470723Y-497062D01*
Y-496896D01*
X470850Y-496812D01*
X470977Y-496896D01*
Y-497062D01*
X470850Y-497146D01*
G01Y-494896D02*
X470723Y-494812D01*
Y-494646D01*
X470850Y-494562D01*
X470977Y-494646D01*
Y-494812D01*
X470850Y-494896D01*
G01X524488Y811122D02*
G02X537992I6752J0D01*
G02X524488I-6752J0D01*
G01X518523Y1171319D02*
G02X532027I6752J0D01*
G02X518523I-6752J0D01*
G01X531177Y1395413D02*
G02X543775I6299J0D01*
G02X531177I-6299J0D01*
G01X567814Y991220D02*
G02X581318I6752J0D01*
G02X567814I-6752J0D01*
G01X650000Y631890D02*
G02X672047I11023J0D01*
G02X650000I-11024J0D01*
G01X723870Y294362D02*
Y260110D01*
G02X684500I-19685J0D01*
G01Y294362D01*
G02X723870I19685J0D01*
G01X696654Y1714961D02*
G02X718701I11023J0D01*
G02X696654I-11024J0D01*
G01X743917Y605413D02*
G02X783287I19685J0D01*
G02X743917I-19685J0D01*
G01X789764Y87795D02*
G02X811811I11023J0D01*
G02X789764I-11023J0D01*
G01X794864Y204724D02*
G02X816517I10827J0D01*
G02X794864I-10826J0D01*
G01X833366Y1420331D02*
G02X849114I7874J0D01*
G02X833366I-7874J0D01*
G01X896260Y175197D02*
G02X904134I3937J0D01*
G02X896260I-3937J0D01*
G01X936673Y311614D02*
X920807D01*
G02X936673I7933J10039D01*
G01X920669Y757874D02*
G02X942717I11024J0D01*
G02X920669I-11024J0D01*
G01Y1072835D02*
G02X942717I11024J0D01*
G02X920669I-11024J0D01*
G01Y1387795D02*
G02X942717I11024J0D01*
G02X920669I-11024J0D01*
G01X940748Y155217D02*
G02X948622I3937J0D01*
G02X940748I-3937J0D01*
G01X1008366Y1420331D02*
G02X1024114I7874J0D01*
G02X1008366I-7874J0D01*
G01X1034843Y87795D02*
G02X1056890I11024J0D01*
G02X1034843I-11023J0D01*
G01X1046832Y204724D02*
G02X1068486I10827J0D01*
G02X1046832I-10827J0D01*
G01X1074390Y605378D02*
G02X1113760I19685J0D01*
G02X1074390I-19685J0D01*
G01X1173240Y294335D02*
Y260083D01*
G02X1133870I-19685J0D01*
G01Y294335D01*
G02X1173240I19685J0D01*
G01X1125512Y1653543D02*
G02X1142047I8267J0D01*
G02X1125512I-8268J0D01*
G01X1144685Y1714961D02*
G02X1166732I11023J0D01*
G02X1144685I-11024J0D01*
G01X1241535Y269488D02*
G02X1253740I6103J0D01*
G02X1241535I-6102J0D01*
G01X1260236Y631890D02*
G02X1282283I11023J0D01*
G02X1260236I-11023J0D01*
G01X1276161Y991220D02*
G02X1289665I6752J0D01*
G02X1276161I-6752J0D01*
G01X1292342Y1391831D02*
G02X1304940I6299J0D01*
G02X1292342I-6299J0D01*
G01X1319488Y811122D02*
G02X1332992I6752J0D01*
G02X1319488I-6752J0D01*
G01X1325452Y1171319D02*
G02X1338956I6752J0D01*
G02X1325452I-6752J0D01*
G01X1399016Y112008D02*
G02X1411220I6102J0D01*
G02X1399016I-6102J0D01*
G01X1422677Y1698268D02*
G02X1410197I-6240J0D01*
G02X1422677I6240J0D01*
G01X1450782Y1714961D02*
G02X1472829I11023J0D01*
G02X1450782I-11024J0D01*
G01X1488583Y87795D02*
G02X1510630I11024J0D01*
G02X1488583I-11023J0D01*
G01X1500629Y811122D02*
G02X1514133I6752J0D01*
G02X1500629I-6752J0D01*
G01X1494665Y1171319D02*
G02X1508169I6752J0D01*
G02X1494665I-6752J0D01*
G01X1507318Y1395413D02*
G02X1519917I6299J0D01*
G02X1507318I-6300J0D01*
G01X1543956Y991220D02*
G02X1557460I6752J0D01*
G02X1543956I-6752J0D01*
G01X1700012Y294362D02*
Y260110D01*
G02X1660642I-19685J0D01*
G01Y294362D01*
G02X1700012I19685J0D01*
G01X1660547Y1644764D02*
Y1671142D01*
G02X1699917I19685J0D01*
G01Y1644764D01*
G02X1660547I-19685J0D01*
G01X1720059Y605413D02*
G02X1759429I19685J0D01*
G02X1720059I-19685J0D01*
G01X1760827Y1714961D02*
G02X1773031I6102J0D01*
G02X1760827I-6102J0D01*
G01X1799528Y1420331D02*
G02X1838898I19685J0D01*
G02X1799528I-19685J0D01*
G01X1795276Y1714961D02*
G02X1817323I11024J0D01*
G02X1795276I-11023J0D01*
G01X1805748Y631890D02*
G02X1827795I11024J0D01*
G02X1805748I-11023J0D01*
G01Y1368898D02*
G02X1827795I11024J0D01*
G02X1805748I-11023J0D01*
G01X1818898Y87795D02*
G02X1840945I11023J0D01*
G02X1818898I-11023J0D01*
G01X1835827Y133465D02*
Y127165D01*
G02X1823622I-6103J0D01*
G01Y133465D01*
G02X1835827I6102J0D01*
G01X-984580Y-698988D02*
Y4193602D01*
X5868320D01*
Y-698988D01*
X-984580D01*
G01X7723Y-521204D02*
X7253Y-520889D01*
X6705Y-520679D01*
X6078D01*
X5373Y-520994D01*
X4825Y-521519D01*
X4433Y-522149D01*
X4120Y-523199D01*
X4042Y-524144D01*
X4198Y-525089D01*
X4433Y-525719D01*
X4903Y-526349D01*
X5452Y-526769D01*
X6000Y-526979D01*
X6548D01*
X7097Y-526769D01*
X7567Y-526454D01*
X7958Y-526034D01*
G01X11360Y-520679D02*
X13240D01*
G01X12300D02*
Y-526979D01*
G01X11360D02*
X13240D01*
G01X18600Y-520679D02*
Y-526979D01*
G01X16798Y-520679D02*
X20402D01*
G01X24900Y-526979D02*
Y-524144D01*
X23333Y-520679D01*
G01X26467D02*
X24900Y-524144D01*
G01X35777Y-525719D02*
X36247Y-526454D01*
X36873Y-526874D01*
X37578Y-526979D01*
X38205Y-526874D01*
X38832Y-526349D01*
X39223Y-525719D01*
X39302Y-525089D01*
X39145Y-524354D01*
X38597Y-523829D01*
X38048Y-523619D01*
X37343D01*
G01X38048D02*
X38518Y-523304D01*
X38910Y-522779D01*
X39067Y-522149D01*
X38910Y-521519D01*
X38518Y-520994D01*
X37813Y-520679D01*
X37108Y-520784D01*
X36403Y-521204D01*
G01X42077Y-525719D02*
X42547Y-526454D01*
X43173Y-526874D01*
X43878Y-526979D01*
X44505Y-526874D01*
X45132Y-526349D01*
X45523Y-525719D01*
X45602Y-525089D01*
X45445Y-524354D01*
X44897Y-523829D01*
X44348Y-523619D01*
X43643D01*
G01X44348D02*
X44818Y-523304D01*
X45210Y-522779D01*
X45367Y-522149D01*
X45210Y-521519D01*
X44818Y-520994D01*
X44113Y-520679D01*
X43408Y-520784D01*
X42703Y-521204D01*
G01X48377Y-525719D02*
X48847Y-526454D01*
X49473Y-526874D01*
X50178Y-526979D01*
X50805Y-526874D01*
X51432Y-526349D01*
X51823Y-525719D01*
X51902Y-525089D01*
X51745Y-524354D01*
X51197Y-523829D01*
X50648Y-523619D01*
X49943D01*
G01X50648D02*
X51118Y-523304D01*
X51510Y-522779D01*
X51667Y-522149D01*
X51510Y-521519D01*
X51118Y-520994D01*
X50413Y-520679D01*
X49708Y-520784D01*
X49003Y-521204D01*
G01X56243Y-526979D02*
X56400Y-525614D01*
X56635Y-524459D01*
X56948Y-523409D01*
X57340Y-522254D01*
X57967Y-520679D01*
X54833D01*
G01X62543Y-526979D02*
X62700Y-525614D01*
X62935Y-524459D01*
X63248Y-523409D01*
X63640Y-522254D01*
X64267Y-520679D01*
X61133D01*
G01X68843Y-528134D02*
X69157Y-526769D01*
G01X75300Y-520679D02*
Y-526979D01*
G01X73498Y-520679D02*
X77102D01*
G01X79642Y-526979D02*
X81600Y-520679D01*
X83558Y-526979D01*
G01X82853Y-524774D02*
X80347D01*
G01X86960Y-520679D02*
X88840D01*
G01X87900D02*
Y-526979D01*
G01X86960D02*
X88840D01*
G01X91850Y-520679D02*
X92947Y-526979D01*
X94200Y-520679D01*
X95453Y-526979D01*
X96550Y-520679D01*
G01X98542Y-526979D02*
X100500Y-520679D01*
X102458Y-526979D01*
G01X101753Y-524774D02*
X99247D01*
G01X104998Y-526979D02*
Y-520679D01*
X108602Y-526979D01*
Y-520679D01*
G01X119008Y-529079D02*
X118225Y-528029D01*
X117833Y-526979D01*
Y-522779D01*
X118225Y-521729D01*
X119008Y-520679D01*
G01X130433Y-526979D02*
Y-520679D01*
X132392D01*
X133018Y-520994D01*
X133410Y-521414D01*
X133567Y-522254D01*
X133410Y-523094D01*
X132940Y-523619D01*
X132392Y-523934D01*
X130433D01*
G01X132392D02*
X133567Y-526979D01*
G01X138300Y-527189D02*
X138143Y-527084D01*
Y-526874D01*
X138300Y-526769D01*
X138457Y-526874D01*
Y-527084D01*
X138300Y-527189D01*
G01X144600Y-526979D02*
X143973Y-526874D01*
X143425Y-526454D01*
X142955Y-525824D01*
X142642Y-525089D01*
X142485Y-524249D01*
Y-523409D01*
X142642Y-522569D01*
X142955Y-521834D01*
X143425Y-521204D01*
X143973Y-520784D01*
X144600Y-520679D01*
X145227Y-520784D01*
X145775Y-521204D01*
X146245Y-521834D01*
X146558Y-522569D01*
X146715Y-523409D01*
Y-524249D01*
X146558Y-525089D01*
X146245Y-525824D01*
X145775Y-526454D01*
X145227Y-526874D01*
X144600Y-526979D01*
G01X150900Y-527189D02*
X150743Y-527084D01*
Y-526874D01*
X150900Y-526769D01*
X151057Y-526874D01*
Y-527084D01*
X150900Y-527189D01*
G01X158923Y-521204D02*
X158453Y-520889D01*
X157905Y-520679D01*
X157278D01*
X156573Y-520994D01*
X156025Y-521519D01*
X155633Y-522149D01*
X155320Y-523199D01*
X155242Y-524144D01*
X155398Y-525089D01*
X155633Y-525719D01*
X156103Y-526349D01*
X156652Y-526769D01*
X157200Y-526979D01*
X157748D01*
X158297Y-526769D01*
X158767Y-526454D01*
X159158Y-526034D01*
G01X163500Y-527189D02*
X163343Y-527084D01*
Y-526874D01*
X163500Y-526769D01*
X163657Y-526874D01*
Y-527084D01*
X163500Y-527189D01*
G01X170192Y-529079D02*
X170975Y-528029D01*
X171367Y-526979D01*
Y-522779D01*
X170975Y-521729D01*
X170192Y-520679D01*
G01X6470Y-513829D02*
X8037D01*
Y-515719D01*
X7567Y-516349D01*
X7018Y-516769D01*
X6235Y-516979D01*
X5452Y-516769D01*
X4903Y-516349D01*
X4433Y-515719D01*
X4120Y-514984D01*
X3963Y-514144D01*
Y-513409D01*
X4120Y-512779D01*
X4433Y-512044D01*
X4903Y-511414D01*
X5373Y-510994D01*
X6000Y-510679D01*
X6548D01*
X7175Y-510889D01*
X7645Y-511309D01*
G01X10577Y-510679D02*
Y-515194D01*
X10890Y-516139D01*
X11517Y-516769D01*
X12300Y-516979D01*
X13083Y-516769D01*
X13710Y-516139D01*
X14023Y-515194D01*
Y-510679D01*
G01X17660D02*
X19540D01*
G01X18600D02*
Y-516979D01*
G01X17660D02*
X19540D01*
G01X23255Y-516139D02*
X23882Y-516664D01*
X24587Y-516979D01*
X25213D01*
X25840Y-516664D01*
X26310Y-516139D01*
X26545Y-515404D01*
X26388Y-514669D01*
X25997Y-514039D01*
X25292Y-513619D01*
X24352Y-513409D01*
X23803Y-512989D01*
X23568Y-512254D01*
X23725Y-511519D01*
X24117Y-510994D01*
X24665Y-510679D01*
X25213D01*
X25762Y-510889D01*
X26232Y-511414D01*
G01X29555Y-516979D02*
Y-510679D01*
G01X32845D02*
Y-516979D01*
G01Y-513829D02*
X29555D01*
G01X35542Y-516979D02*
X37500Y-510679D01*
X39458Y-516979D01*
G01X38753Y-514774D02*
X36247D01*
G01X41998Y-516979D02*
Y-510679D01*
X45602Y-516979D01*
Y-510679D01*
G01X54677Y-516979D02*
Y-510679D01*
X56243D01*
X56870Y-510994D01*
X57340Y-511414D01*
X57732Y-512044D01*
X58045Y-512779D01*
X58123Y-513829D01*
X58045Y-514879D01*
X57732Y-515614D01*
X57340Y-516244D01*
X56870Y-516664D01*
X56243Y-516979D01*
X54677D01*
G01X61760Y-510679D02*
X63640D01*
G01X62700D02*
Y-516979D01*
G01X61760D02*
X63640D01*
G01X67355Y-516139D02*
X67982Y-516664D01*
X68687Y-516979D01*
X69313D01*
X69940Y-516664D01*
X70410Y-516139D01*
X70645Y-515404D01*
X70488Y-514669D01*
X70097Y-514039D01*
X69392Y-513619D01*
X68452Y-513409D01*
X67903Y-512989D01*
X67668Y-512254D01*
X67825Y-511519D01*
X68217Y-510994D01*
X68765Y-510679D01*
X69313D01*
X69862Y-510889D01*
X70332Y-511414D01*
G01X75300Y-510679D02*
Y-516979D01*
G01X73498Y-510679D02*
X77102D01*
G01X81600Y-517189D02*
X81443Y-517084D01*
Y-516874D01*
X81600Y-516769D01*
X81757Y-516874D01*
Y-517084D01*
X81600Y-517189D01*
G01X87743Y-518134D02*
X88057Y-516769D01*
G01X94200Y-510679D02*
Y-516979D01*
G01X92398Y-510679D02*
X96002D01*
G01X98542Y-516979D02*
X100500Y-510679D01*
X102458Y-516979D01*
G01X101753Y-514774D02*
X99247D01*
G01X106800Y-516979D02*
X106173Y-516874D01*
X105625Y-516454D01*
X105155Y-515824D01*
X104842Y-515089D01*
X104685Y-514249D01*
Y-513409D01*
X104842Y-512569D01*
X105155Y-511834D01*
X105625Y-511204D01*
X106173Y-510784D01*
X106800Y-510679D01*
X107427Y-510784D01*
X107975Y-511204D01*
X108445Y-511834D01*
X108758Y-512569D01*
X108915Y-513409D01*
Y-514249D01*
X108758Y-515089D01*
X108445Y-515824D01*
X107975Y-516454D01*
X107427Y-516874D01*
X106800Y-516979D01*
G01X113100D02*
Y-514144D01*
X111533Y-510679D01*
G01X114667D02*
X113100Y-514144D01*
G01X117677Y-510679D02*
Y-515194D01*
X117990Y-516139D01*
X118617Y-516769D01*
X119400Y-516979D01*
X120183Y-516769D01*
X120810Y-516139D01*
X121123Y-515194D01*
Y-510679D01*
G01X123742Y-516979D02*
X125700Y-510679D01*
X127658Y-516979D01*
G01X126953Y-514774D02*
X124447D01*
G01X130198Y-516979D02*
Y-510679D01*
X133802Y-516979D01*
Y-510679D01*
G01X4198Y-506979D02*
Y-500679D01*
X7802Y-506979D01*
Y-500679D01*
G01X12300Y-506979D02*
X11673Y-506874D01*
X11125Y-506454D01*
X10655Y-505824D01*
X10342Y-505089D01*
X10185Y-504249D01*
Y-503409D01*
X10342Y-502569D01*
X10655Y-501834D01*
X11125Y-501204D01*
X11673Y-500784D01*
X12300Y-500679D01*
X12927Y-500784D01*
X13475Y-501204D01*
X13945Y-501834D01*
X14258Y-502569D01*
X14415Y-503409D01*
Y-504249D01*
X14258Y-505089D01*
X13945Y-505824D01*
X13475Y-506454D01*
X12927Y-506874D01*
X12300Y-506979D01*
G01X18600Y-507189D02*
X18443Y-507084D01*
Y-506874D01*
X18600Y-506769D01*
X18757Y-506874D01*
Y-507084D01*
X18600Y-507189D01*
G01X23412Y-501729D02*
X23882Y-501099D01*
X24430Y-500784D01*
X25057Y-500679D01*
X25840Y-500889D01*
X26388Y-501414D01*
X26545Y-502044D01*
X26467Y-502674D01*
X26153Y-503199D01*
X24587Y-504249D01*
X23882Y-504984D01*
X23412Y-506034D01*
X23255Y-506979D01*
X26545D01*
G01X31200D02*
Y-500679D01*
X30260Y-501939D01*
G01Y-506979D02*
X32140D01*
G01X37500D02*
Y-500679D01*
X36560Y-501939D01*
G01Y-506979D02*
X38440D01*
G01X43643Y-508134D02*
X43957Y-506769D01*
G01X47750Y-500679D02*
X48847Y-506979D01*
X50100Y-500679D01*
X51353Y-506979D01*
X52450Y-500679D01*
G01X57967Y-506979D02*
X54833D01*
Y-500679D01*
X57967D01*
G01X56713Y-503724D02*
X54833D01*
G01X60898Y-506979D02*
Y-500679D01*
X64502Y-506979D01*
Y-500679D01*
G01X67355Y-506979D02*
Y-500679D01*
G01X70645D02*
Y-506979D01*
G01Y-503829D02*
X67355D01*
G01X73577Y-500679D02*
Y-505194D01*
X73890Y-506139D01*
X74517Y-506769D01*
X75300Y-506979D01*
X76083Y-506769D01*
X76710Y-506139D01*
X77023Y-505194D01*
Y-500679D01*
G01X79642Y-506979D02*
X81600Y-500679D01*
X83558Y-506979D01*
G01X82853Y-504774D02*
X80347D01*
G01X92712Y-501729D02*
X93182Y-501099D01*
X93730Y-500784D01*
X94357Y-500679D01*
X95140Y-500889D01*
X95688Y-501414D01*
X95845Y-502044D01*
X95767Y-502674D01*
X95453Y-503199D01*
X93887Y-504249D01*
X93182Y-504984D01*
X92712Y-506034D01*
X92555Y-506979D01*
X95845D01*
G01X98698D02*
Y-500679D01*
X102302Y-506979D01*
Y-500679D01*
G01X105077Y-506979D02*
Y-500679D01*
X106643D01*
X107270Y-500994D01*
X107740Y-501414D01*
X108132Y-502044D01*
X108445Y-502779D01*
X108523Y-503829D01*
X108445Y-504879D01*
X108132Y-505614D01*
X107740Y-506244D01*
X107270Y-506664D01*
X106643Y-506979D01*
X105077D01*
G01X117833D02*
Y-500679D01*
X119792D01*
X120418Y-500994D01*
X120810Y-501414D01*
X120967Y-502254D01*
X120810Y-503094D01*
X120340Y-503619D01*
X119792Y-503934D01*
X117833D01*
G01X119792D02*
X120967Y-506979D01*
G01X123977D02*
Y-500679D01*
X125543D01*
X126170Y-500994D01*
X126640Y-501414D01*
X127032Y-502044D01*
X127345Y-502779D01*
X127423Y-503829D01*
X127345Y-504879D01*
X127032Y-505614D01*
X126640Y-506244D01*
X126170Y-506664D01*
X125543Y-506979D01*
X123977D01*
G01X132000Y-507189D02*
X131843Y-507084D01*
Y-506874D01*
X132000Y-506769D01*
X132157Y-506874D01*
Y-507084D01*
X132000Y-507189D01*
G01X28300Y-494279D02*
X25780Y-493862D01*
X23575Y-492196D01*
X21685Y-489696D01*
X20425Y-486779D01*
X19795Y-483446D01*
Y-480112D01*
X20425Y-476779D01*
X21685Y-473862D01*
X23575Y-471363D01*
X25780Y-469696D01*
X28300Y-469279D01*
X30820Y-469696D01*
X33025Y-471363D01*
X34915Y-473862D01*
X36175Y-476779D01*
X36805Y-480112D01*
Y-483446D01*
X36175Y-486779D01*
X34915Y-489696D01*
X33025Y-492196D01*
X30820Y-493862D01*
X28300Y-494279D01*
G01X30820Y-487612D02*
X34600Y-494279D01*
G01X48145Y-477613D02*
Y-489279D01*
X49405Y-492196D01*
X51295Y-493862D01*
X53500Y-494279D01*
X55705Y-493862D01*
X57595Y-492196D01*
X58855Y-489279D01*
G01Y-494279D02*
Y-477613D01*
G01X84370Y-494279D02*
Y-477613D01*
G01Y-480529D02*
X83110Y-478863D01*
X81220Y-478029D01*
X79015Y-477613D01*
X76810Y-478446D01*
X74920Y-480112D01*
X73660Y-482613D01*
X73030Y-485946D01*
X73660Y-489279D01*
X74920Y-491780D01*
X76810Y-493446D01*
X79015Y-494279D01*
X81220Y-493862D01*
X83110Y-492613D01*
X84370Y-490946D01*
G01X98545Y-494279D02*
Y-477613D01*
G01Y-481779D02*
X99805Y-479696D01*
X101695Y-478029D01*
X104215Y-477613D01*
X106420Y-478029D01*
X108310Y-479696D01*
X109255Y-482613D01*
Y-494279D01*
G01X129100Y-469279D02*
Y-494279D01*
G01X124690Y-477613D02*
X133510D01*
G01X159970Y-494279D02*
Y-477613D01*
G01Y-480529D02*
X158710Y-478863D01*
X156820Y-478029D01*
X154615Y-477613D01*
X152410Y-478446D01*
X150520Y-480112D01*
X149260Y-482613D01*
X148630Y-485946D01*
X149260Y-489279D01*
X150520Y-491780D01*
X152410Y-493446D01*
X154615Y-494279D01*
X156820Y-493862D01*
X158710Y-492613D01*
X159970Y-490946D01*
G01X75230Y337402D02*
G03I-25950J0D01*
G01X28999Y1258564D02*
Y1255364D01*
G01X35199Y1258564D02*
X28999D01*
G01Y1255364D02*
X35199D01*
G01X28999Y1254565D02*
Y1251365D01*
G01X35199Y1254565D02*
X28999D01*
G01Y1251365D02*
X35199D01*
G01X29099Y1259964D02*
X35099D01*
G01X29099Y1271964D02*
Y1259964D01*
G01X35099Y1271964D02*
X29099D01*
G01X61246Y1420330D02*
G03I-22900J0D01*
G01X67820Y1511291D02*
G03I-25950J0D01*
G01X44158Y395008D02*
Y391808D01*
G01X50358Y395008D02*
X44158D01*
G01Y391808D02*
X50358D01*
G01X43991Y388593D02*
Y385393D01*
G01X50191Y388593D02*
X43991D01*
G01Y385393D02*
X50191D01*
G01X42646Y437302D02*
Y447102D01*
G01X45210Y437302D02*
X42646D01*
G01X35355Y439530D02*
Y442730D01*
G01X29155Y439530D02*
X35355D01*
G01X29155Y442730D02*
Y439530D01*
G01X35355Y442730D02*
X29155D01*
G01X35355Y443919D02*
Y447119D01*
G01X29155Y443919D02*
X35355D01*
G01X29155Y447119D02*
Y443919D01*
G01X54643Y457665D02*
Y455443D01*
X54490Y454978D01*
X54183Y454668D01*
X53800Y454565D01*
X53417Y454668D01*
X53110Y454978D01*
X52957Y455443D01*
Y457665D01*
G01X51543Y455030D02*
X51313Y454772D01*
X51045Y454617D01*
X50700Y454565D01*
X50355Y454668D01*
X50087Y454875D01*
X49895Y455237D01*
X49857Y455650D01*
X49933Y456063D01*
X50125Y456322D01*
X50393Y456528D01*
X50662Y456580D01*
X50930Y456528D01*
X51275Y456322D01*
X51160Y457665D01*
X50125D01*
G01X48328Y457148D02*
X48098Y457458D01*
X47830Y457613D01*
X47523Y457665D01*
X47140Y457562D01*
X46872Y457303D01*
X46795Y456993D01*
X46833Y456683D01*
X46987Y456425D01*
X47753Y455908D01*
X48098Y455547D01*
X48328Y455030D01*
X48405Y454565D01*
X46795D01*
G01X44500Y457665D02*
X44807Y457562D01*
X45037Y457303D01*
X45190Y456993D01*
X45305Y456580D01*
X45343Y456115D01*
X45305Y455650D01*
X45190Y455237D01*
X45037Y454927D01*
X44807Y454668D01*
X44500Y454565D01*
X44193Y454668D01*
X43963Y454927D01*
X43810Y455237D01*
X43695Y455650D01*
X43657Y456115D01*
X43695Y456580D01*
X43810Y456993D01*
X43963Y457303D01*
X44193Y457562D01*
X44500Y457665D01*
G01X41400Y454565D02*
Y457665D01*
X41860Y457045D01*
G01Y454565D02*
X40940D01*
G01X42646Y447102D02*
X45660D01*
G01X35355Y447119D02*
X29155D01*
G01X44668Y720774D02*
Y723974D01*
G01X38468Y720774D02*
X44668D01*
G01X38468Y723974D02*
Y720774D01*
G01X44668Y723974D02*
X38468D01*
G01X44668Y725274D02*
Y728474D01*
G01X38468Y725274D02*
X44668D01*
G01X38468Y728474D02*
Y725274D01*
G01X44668Y728474D02*
X38468D01*
G01X40522Y752854D02*
X52046D01*
G01X40522Y765058D02*
Y752854D01*
G01X52627Y772003D02*
Y769781D01*
X52474Y769316D01*
X52167Y769006D01*
X51784Y768903D01*
X51401Y769006D01*
X51094Y769316D01*
X50941Y769781D01*
Y772003D01*
G01X49412Y771486D02*
X49182Y771796D01*
X48914Y771951D01*
X48607Y772003D01*
X48224Y771900D01*
X47956Y771641D01*
X47879Y771331D01*
X47917Y771021D01*
X48071Y770763D01*
X48837Y770246D01*
X49182Y769885D01*
X49412Y769368D01*
X49489Y768903D01*
X47879D01*
G01X46236Y769265D02*
X45967Y769006D01*
X45661Y768903D01*
X45354Y769006D01*
X45086Y769316D01*
X44894Y769781D01*
X44817Y770246D01*
Y770815D01*
X44894Y771280D01*
X45086Y771693D01*
X45316Y771900D01*
X45584Y772003D01*
X45891Y771900D01*
X46121Y771693D01*
X46274Y771383D01*
X46351Y770970D01*
X46274Y770608D01*
X46082Y770246D01*
X45852Y770040D01*
X45584Y769988D01*
X45277Y770091D01*
X45047Y770350D01*
X44817Y770815D01*
G01X43284Y765058D02*
X40522D01*
G01X46284Y761956D02*
X43284Y765058D01*
G01X39239Y767832D02*
X42439D01*
G01X39239Y774032D02*
Y767832D01*
G01X42439D02*
Y774032D01*
G01D02*
X39239D01*
G01X35199Y1255364D02*
Y1258564D01*
G01X42445Y1252800D02*
Y1256000D01*
G01X36245Y1252800D02*
X42445D01*
G01X36245Y1256000D02*
Y1252800D01*
G01X42445Y1256000D02*
X36245D01*
G01X44999Y1258564D02*
Y1255364D01*
G01X51199Y1258564D02*
X44999D01*
G01Y1255364D02*
X51199D01*
G01X35199Y1251365D02*
Y1254565D01*
G01X45099Y1259964D02*
X51099D01*
G01X45099Y1271964D02*
Y1259964D01*
G01X51099Y1271964D02*
X45099D01*
G01X35099Y1259964D02*
Y1271964D01*
G01X60711Y391479D02*
X66911D01*
G01X60711Y394679D02*
Y391479D01*
G01X66911Y394679D02*
X60711D01*
G01X59144Y395396D02*
Y401596D01*
G01X55944Y395396D02*
X59144D01*
G01X55944Y401596D02*
Y395396D01*
G01X55338Y395370D02*
Y401570D01*
G01X52138Y395370D02*
X55338D01*
G01X52138Y401570D02*
Y395370D01*
G01X60713Y386862D02*
X66913D01*
G01X60713Y390062D02*
Y386862D01*
G01X66913Y390062D02*
X60713D01*
G01X50358Y391808D02*
Y395008D01*
G01X50191Y385393D02*
Y388593D01*
G01X59144Y401596D02*
X55944D01*
G01X55338Y401570D02*
X52138D01*
G01X52446Y447102D02*
Y437302D01*
G01D02*
X49880D01*
G01X62361Y440059D02*
X59161D01*
G01Y433859D02*
X62361D01*
G01X59161Y440059D02*
Y433859D01*
G01X58322Y440126D02*
X55122D01*
G01X58322Y433926D02*
Y440126D01*
G01X55122Y433926D02*
X58322D01*
G01X55122Y440126D02*
Y433926D01*
G01X60828Y445277D02*
Y442077D01*
G01X67028Y445277D02*
X60828D01*
G01Y442077D02*
X67028D01*
G01X49540Y447102D02*
X52446D01*
G01X52968Y720774D02*
Y723974D01*
G01X46768Y720774D02*
X52968D01*
G01X46768Y723974D02*
Y720774D01*
G01X52968Y723974D02*
X46768D01*
G01X52968Y725274D02*
Y728474D01*
G01X46768Y725274D02*
X52968D01*
G01X46768Y728474D02*
Y725274D01*
G01X52968Y728474D02*
X46768D01*
G01X52046Y752854D02*
Y765058D01*
G01X49386D02*
X46284Y761956D01*
G01X52046Y765058D02*
X49386D01*
G01X58699Y1258564D02*
Y1255364D01*
G01X64899Y1258564D02*
X58699D01*
G01Y1255364D02*
X64899D01*
G01X51199D02*
Y1258564D01*
G01X63375Y1249561D02*
X60175D01*
G01Y1243361D02*
X63375D01*
G01X60175Y1249561D02*
Y1243361D01*
G01X51099Y1259964D02*
Y1271964D01*
G01X58799Y1259964D02*
X64799D01*
G01X58799Y1271964D02*
Y1259964D01*
G01X64799Y1271964D02*
X58799D01*
G01X66997Y380028D02*
Y386228D01*
G01X63797Y380028D02*
X66997D01*
G01X63797Y386228D02*
Y380028D01*
G01X71598Y380137D02*
Y386337D01*
G01X68398Y380137D02*
X71598D01*
G01X68398Y386337D02*
Y380137D01*
G01X72569Y380092D02*
X75769D01*
G01X72569Y386292D02*
Y380092D01*
G01X75769D02*
Y386292D01*
G01X66911Y391479D02*
Y394679D01*
G01X66997Y386228D02*
X63797D01*
G01X71598Y386337D02*
X68398D01*
G01X66913Y386862D02*
Y390062D01*
G01X75769Y386292D02*
X72569D01*
G01X62361Y433859D02*
Y440059D01*
G01X67028Y442077D02*
Y445277D01*
G01X75521Y691481D02*
X78721D01*
G01X75521Y697681D02*
Y691481D01*
G01X78721Y697681D02*
X75521D01*
G01X74881Y697711D02*
X71681D01*
G01X74881Y691511D02*
Y697711D01*
G01X71681Y691511D02*
X74881D01*
G01X71681Y697711D02*
Y691511D01*
G01X72884Y753126D02*
Y756326D01*
G01X66684Y753126D02*
X72884D01*
G01X66684Y756326D02*
Y753126D01*
G01X66790Y764764D02*
Y761564D01*
G01X72990Y764764D02*
X66790D01*
G01X72990Y761564D02*
Y764764D01*
G01X66790Y761564D02*
X72990D01*
G01X72884Y756326D02*
X66684D01*
G01X72884Y757646D02*
Y760846D01*
G01X66684Y757646D02*
X72884D01*
G01X66684Y760846D02*
Y757646D01*
G01X72884Y760846D02*
X66684D01*
G01X64899Y1255364D02*
Y1258564D01*
G01X74699D02*
Y1255364D01*
G01X80899Y1258564D02*
X74699D01*
G01Y1255364D02*
X80899D01*
G01X72377Y1252993D02*
Y1256193D01*
G01X66177Y1252993D02*
X72377D01*
G01X66177Y1256193D02*
Y1252993D01*
G01X72377Y1256193D02*
X66177D01*
G01X63375Y1243361D02*
Y1249561D01*
G01X74799Y1259964D02*
X80799D01*
G01X74799Y1271964D02*
Y1259964D01*
G01X80799Y1271964D02*
X74799D01*
G01X64799Y1259964D02*
Y1271964D01*
G01X83178Y661241D02*
Y658041D01*
G01X89378Y661241D02*
X83178D01*
G01Y658041D02*
X89378D01*
G01D02*
Y661241D01*
G01Y664741D02*
X83178D01*
G01D02*
Y661541D01*
G01D02*
X89378D01*
G01D02*
Y664741D01*
G01X85440Y669552D02*
Y666352D01*
G01X91640Y669552D02*
X85440D01*
G01Y666352D02*
X91640D01*
G01D02*
Y669552D01*
G01X93608Y672281D02*
Y675481D01*
G01X87408D02*
Y672281D01*
G01D02*
X93608D01*
G01Y676281D02*
Y679481D01*
G01D02*
X87408D01*
G01D02*
Y676281D01*
G01D02*
X93608D01*
G01Y675481D02*
X87408D01*
G01X79371Y691481D02*
X82571D01*
G01X79371Y697681D02*
Y691481D01*
G01X82571Y697681D02*
X79371D01*
G01X82571Y691481D02*
Y697681D01*
G01X91996Y697013D02*
X88796D01*
G01Y690813D02*
X91996D01*
G01X88796Y697013D02*
Y690813D01*
G01X91996D02*
Y697013D01*
G01X78721Y691481D02*
Y697681D01*
G01X84378Y727240D02*
Y724040D01*
G01X90578Y727240D02*
X84378D01*
G01X90578Y724040D02*
Y727240D01*
G01X84378Y724040D02*
X90578D01*
G01X92723Y1242435D02*
Y1248635D01*
G01X89523Y1242435D02*
X92723D01*
G01X89523Y1248635D02*
Y1242435D01*
G01X88399Y1258564D02*
Y1255364D01*
G01X94599Y1258564D02*
X88399D01*
G01Y1255364D02*
X94599D01*
G01X80899D02*
Y1258564D01*
G01X92723Y1248635D02*
X89523D01*
G01X80799Y1259964D02*
Y1271964D01*
G01X88499Y1259964D02*
X94499D01*
G01X88499Y1271964D02*
Y1259964D01*
G01X94499Y1271964D02*
X88499D01*
G01X89520Y1528762D02*
Y1540762D01*
G01X83520Y1528762D02*
X89520D01*
G01X83520Y1540762D02*
Y1528762D01*
G01X89520Y1540762D02*
X83520D01*
G01X96300Y1544372D02*
X93100D01*
G01Y1538172D02*
X96300D01*
G01X93100Y1544372D02*
Y1538172D01*
G01X109550Y491874D02*
Y495074D01*
G01X103350Y491874D02*
X109550D01*
G01X103350Y495074D02*
Y491874D01*
G01Y506974D02*
Y503774D01*
G01X109550Y506974D02*
X103350D01*
G01X109550Y503774D02*
Y506974D01*
G01X103350Y503774D02*
X109550D01*
G01X103350Y510974D02*
Y507774D01*
G01X109550D02*
Y510974D01*
G01X103350Y507774D02*
X109550D01*
G01Y495074D02*
X103350D01*
G01X109550Y510974D02*
X103350D01*
G01Y519525D02*
Y516325D01*
G01X109550Y519525D02*
X103350D01*
G01X109550Y516325D02*
Y519525D01*
G01X103350Y516325D02*
X109550D01*
G01Y511774D02*
Y514974D01*
G01X103350Y511774D02*
X109550D01*
G01X103350Y514974D02*
Y511774D01*
G01X109550Y514974D02*
X103350D01*
G01X140832Y605380D02*
G03I-22900J0D01*
G01X107600Y635762D02*
X110800D01*
G01X107600Y641962D02*
Y635762D01*
G01X103800Y637962D02*
X107000D01*
G01X103800Y644162D02*
Y637962D01*
G01X107000D02*
Y644162D01*
G01X110800Y641962D02*
X107600D01*
G01X94843Y651439D02*
Y648239D01*
G01X101043Y651439D02*
X94843D01*
G01X101043Y648239D02*
Y651439D01*
G01X94843Y648239D02*
X101043D01*
G01X107000Y644162D02*
X103800D01*
G01X94913Y643749D02*
Y640549D01*
G01X101113Y643749D02*
X94913D01*
G01X101113Y640549D02*
Y643749D01*
G01X94913Y640549D02*
X101113D01*
G01X94883Y647609D02*
Y644409D01*
G01X101083Y647609D02*
X94883D01*
G01X101083Y644409D02*
Y647609D01*
G01X94883Y644409D02*
X101083D01*
G01X97476Y689103D02*
Y695303D01*
G01X94276Y689103D02*
X97476D01*
G01X94276Y695303D02*
Y689103D01*
G01X97916Y689123D02*
X101116D01*
G01X97916Y695323D02*
Y689123D01*
G01X101116D02*
Y695323D01*
G01X97476Y695303D02*
X94276D01*
G01X101116Y695323D02*
X97916D01*
G01X98179Y757344D02*
X101379D01*
G01X98179Y763544D02*
Y757344D01*
G01X101379Y763544D02*
X98179D01*
G01X101379Y757344D02*
Y763544D01*
G01X102179Y757344D02*
X105379D01*
G01X102179Y763544D02*
Y757344D01*
G01X105379Y763544D02*
X102179D01*
G01X105379Y757344D02*
Y763544D01*
G01X106179Y757344D02*
X109379D01*
G01X106179Y763544D02*
Y757344D01*
G01X109379Y763544D02*
X106179D01*
G01X109379Y757344D02*
Y763544D01*
G01X94179Y757344D02*
X97379D01*
G01X94179Y763544D02*
Y757344D01*
G01X97379Y763544D02*
X94179D01*
G01X97379Y757344D02*
Y763544D01*
G01X94599Y1255364D02*
Y1258564D01*
G01X104399D02*
Y1255364D01*
G01X110599Y1258564D02*
X104399D01*
G01Y1255364D02*
X110599D01*
G01X101812Y1252864D02*
Y1256064D01*
G01X95612Y1252864D02*
X101812D01*
G01X95612Y1256064D02*
Y1252864D01*
G01X101812Y1256064D02*
X95612D01*
G01X104499Y1259964D02*
X110499D01*
G01X104499Y1271964D02*
Y1259964D01*
G01X110499Y1271964D02*
X104499D01*
G01X94499Y1259964D02*
Y1271964D01*
G01X96300Y1538172D02*
Y1544372D01*
G01X115624Y503238D02*
Y500038D01*
G01X121824Y503238D02*
X115624D01*
G01X121824Y500038D02*
Y503238D01*
G01X115624Y500038D02*
X121824D01*
G01X115654Y509477D02*
Y506277D01*
G01X121854Y509477D02*
X115654D01*
G01X121854Y506277D02*
Y509477D01*
G01X115654Y506277D02*
X121854D01*
G01X115654Y514583D02*
Y511383D01*
G01X121854Y514583D02*
X115654D01*
G01X121854Y511383D02*
Y514583D01*
G01X115654Y511383D02*
X121854D01*
G01X110897Y512164D02*
X114097D01*
G01X110897Y518364D02*
Y512164D01*
G01X114097Y518364D02*
X110897D01*
G01X114097Y512164D02*
Y518364D01*
G01X110800Y635762D02*
Y641962D01*
G01X111300Y636362D02*
X114500D01*
G01X111300Y642562D02*
Y636362D01*
G01X114500D02*
Y642562D01*
G01X124492Y637043D02*
X127692D01*
G01X124492Y643243D02*
Y637043D01*
G01X124160Y651440D02*
X127360D01*
G01X124160Y657640D02*
Y651440D01*
G01X115900Y644362D02*
Y641162D01*
G01X122100D02*
Y644362D01*
G01X115900Y641162D02*
X122100D01*
G01Y644362D02*
X115900D01*
G01X114500Y642562D02*
X111300D01*
G01X127692Y643243D02*
X124492D01*
G01X119547Y655950D02*
Y659150D01*
G01X113347Y655950D02*
X119547D01*
G01X113347Y659150D02*
Y655950D01*
G01X122500Y648422D02*
Y645222D01*
G01X128700Y648422D02*
X122500D01*
G01Y645222D02*
X128700D01*
G01X119583Y644727D02*
Y647927D01*
G01X113383Y644727D02*
X119583D01*
G01X113383Y647927D02*
Y644727D01*
G01X119583Y647927D02*
X113383D01*
G01X119547Y650134D02*
Y653334D01*
G01X113347Y650134D02*
X119547D01*
G01X113347Y653334D02*
Y650134D01*
G01X119547Y653334D02*
X113347D01*
G01X127360Y657640D02*
X124160D01*
G01X119547Y659150D02*
X113347D01*
G01X126708Y669300D02*
X120508D01*
G01D02*
Y666100D01*
G01X126708D02*
Y669300D01*
G01X120508Y666100D02*
X126708D01*
G01X118099Y1258564D02*
Y1255364D01*
G01X124299Y1258564D02*
X118099D01*
G01X124299Y1255364D02*
Y1258564D01*
G01X118099Y1255364D02*
X124299D01*
G01X110599D02*
Y1258564D01*
G01X125078Y1252928D02*
X131278D01*
G01X125078Y1256128D02*
Y1252928D01*
G01X131278Y1256128D02*
X125078D01*
G01X118099Y1252099D02*
Y1248899D01*
G01X124299Y1252099D02*
X118099D01*
G01X124299Y1248899D02*
Y1252099D01*
G01X118099Y1248899D02*
X124299D01*
G01X110499Y1259964D02*
Y1271964D01*
G01X124199Y1259964D02*
Y1271964D01*
G01X118199Y1259964D02*
X124199D01*
G01X118199Y1271964D02*
Y1259964D01*
G01X124199Y1271964D02*
X118199D01*
G01X142447Y492040D02*
X148647D01*
G01X142447Y495240D02*
Y492040D01*
G01Y500040D02*
X148647D01*
G01X142447Y503240D02*
Y500040D01*
G01X148647Y503240D02*
X142447D01*
G01X148647Y495240D02*
X142447D01*
G01Y496040D02*
X148647D01*
G01X142447Y499240D02*
Y496040D01*
G01X148647Y499240D02*
X142447D01*
G01Y503950D02*
X148647D01*
G01X142447Y507150D02*
Y503950D01*
G01X148647Y507150D02*
X142447D01*
G01X142398Y524371D02*
Y521171D01*
G01X148598Y524371D02*
X142398D01*
G01Y521171D02*
X148598D01*
G01X142397Y517210D02*
X148597D01*
G01X142397Y520410D02*
Y517210D01*
G01X148597Y520410D02*
X142397D01*
G01Y513380D02*
X148597D01*
G01X142397Y516580D02*
Y513380D01*
G01X148597Y516580D02*
X142397D01*
G01X127692Y637043D02*
Y643243D01*
G01X127360Y651440D02*
Y657640D01*
G01X128700Y645222D02*
Y648422D01*
G01X140291Y654519D02*
X134091D01*
G01D02*
Y651319D01*
G01D02*
X140291D01*
G01D02*
Y654519D01*
G01X134091Y658031D02*
Y654831D01*
G01D02*
X140291D01*
G01D02*
Y658031D01*
G01D02*
X134091D01*
G01X141748Y693370D02*
X147948D01*
Y696570D01*
X141748D01*
Y693370D01*
G01X141648Y701670D02*
X147848D01*
Y704870D01*
X141648D01*
Y701670D01*
G01X134429Y756444D02*
X137629D01*
G01X134429Y762644D02*
Y756444D01*
G01X137629Y762644D02*
X134429D01*
G01X137629Y756444D02*
Y762644D01*
G01X142429Y756444D02*
X145629D01*
G01X142429Y762644D02*
Y756444D01*
G01X145629Y762644D02*
X142429D01*
G01X138429Y756444D02*
X141629D01*
G01X138429Y762644D02*
Y756444D01*
G01X141629Y762644D02*
X138429D01*
G01X141629Y756444D02*
Y762644D01*
G01X137873Y1226182D02*
Y1229282D01*
X137107D01*
X136800Y1229127D01*
X136570Y1228920D01*
X136378Y1228610D01*
X136225Y1228249D01*
X136187Y1227732D01*
X136225Y1227215D01*
X136378Y1226854D01*
X136570Y1226544D01*
X136800Y1226337D01*
X137107Y1226182D01*
X137873D01*
G01X133470D02*
Y1229282D01*
X134888Y1227060D01*
X132972D01*
G01X130907Y1226182D02*
X130830Y1226854D01*
X130715Y1227422D01*
X130562Y1227939D01*
X130370Y1228507D01*
X130063Y1229282D01*
X131597D01*
G01X144060Y1240955D02*
Y1238529D01*
G01X136973Y1240753D02*
Y1243953D01*
G01X130773Y1240753D02*
X136973D01*
G01X130773Y1243953D02*
Y1240753D01*
G01X139140Y1256352D02*
X145340D01*
G01X139140Y1259552D02*
Y1256352D01*
G01X134350Y1259242D02*
Y1253042D01*
G01D02*
X137550D01*
G01D02*
Y1259242D01*
G01X131278Y1252928D02*
Y1256128D01*
G01X136973Y1243953D02*
X130773D01*
G01X140199Y1259964D02*
Y1271964D01*
G01X134199Y1259964D02*
X140199D01*
G01X134199Y1271964D02*
Y1259964D01*
G01X140199Y1271964D02*
X134199D01*
G01X145340Y1259552D02*
X139140D01*
G01X137550Y1259242D02*
X134350D01*
G01X145720Y1354212D02*
Y1360412D01*
X142520D01*
Y1354212D01*
X145720D01*
G01X136914Y1564734D02*
X130914D01*
Y1552734D01*
X136914D01*
Y1564734D01*
G01X141704Y1552977D02*
Y1559177D01*
X138504D01*
Y1552977D01*
X141704D01*
G01X140556Y1596555D02*
X146756D01*
G01X140556Y1597852D02*
Y1596555D01*
G01X145260Y1599755D02*
X141570D01*
G01X146756Y1604266D02*
X140556D01*
G01X141570Y1601066D02*
X145260D01*
G01X140556Y1604266D02*
Y1602552D01*
G01X148647Y492040D02*
Y495240D01*
G01Y500040D02*
Y503240D01*
G01Y496040D02*
Y499240D01*
G01X152518Y512695D02*
Y509495D01*
G01D02*
X158718D01*
G01D02*
Y512695D01*
G01X148647Y503950D02*
Y507150D01*
G01X148598Y521171D02*
Y524371D01*
G01X158718Y512695D02*
X152518D01*
G01X148597Y517210D02*
Y520410D01*
G01Y513380D02*
Y516580D01*
G01X145629Y756444D02*
Y762644D01*
G01X146429Y756444D02*
X149629D01*
G01X146429Y762644D02*
Y756444D01*
G01X149629Y762644D02*
X146429D01*
G01X149629Y756444D02*
Y762644D01*
G01X149700Y1230571D02*
X151940D01*
G01X150727Y1228946D02*
Y1232196D01*
G01X150927Y1242758D02*
X152896Y1240790D01*
G01X148958D02*
X150927Y1242758D01*
G01X152896Y1240790D02*
X148958D01*
G01X148171Y1233921D02*
X153683D01*
G01X148171Y1250069D02*
Y1233921D01*
G01X153683D02*
Y1250069D01*
G01X160797Y1238796D02*
X157597D01*
G01Y1232596D02*
X160797D01*
G01X157597Y1238796D02*
Y1232596D01*
G01X152896Y1243152D02*
X148958D01*
G01X148177Y1251221D02*
Y1250721D01*
G01X153677Y1251221D02*
X148177D01*
G01X153677Y1250471D02*
Y1251221D01*
G01X148427Y1250471D02*
X153677D01*
G01X148427Y1250071D02*
Y1250471D01*
G01X148177Y1250071D02*
X148427D01*
G01X148177Y1250771D02*
Y1250071D01*
G01X153677Y1250771D02*
X148177D01*
G01X153677Y1250121D02*
Y1250771D01*
G01X153577Y1250121D02*
X153677D01*
G01X153683Y1250069D02*
X148171D01*
G01X147799Y1258564D02*
Y1255364D01*
G01X153999Y1258564D02*
X147799D01*
G01X153999Y1255364D02*
Y1258564D01*
G01X147799Y1255364D02*
X153999D01*
G01X159089Y1251812D02*
Y1255012D01*
G01X152889Y1251812D02*
X159089D01*
G01X152889Y1255012D02*
Y1251812D01*
G01X159089Y1255012D02*
X152889D01*
G01X145340Y1256352D02*
Y1259552D01*
G01X152499Y1251364D02*
Y1254564D01*
G01X146299Y1251364D02*
X152499D01*
G01X146299Y1254564D02*
Y1251364D01*
G01X152499Y1254564D02*
X146299D01*
G01X153899Y1259964D02*
Y1271964D01*
G01X147899Y1259964D02*
X153899D01*
G01X147899Y1271964D02*
Y1259964D01*
G01X153899Y1271964D02*
X147899D01*
G01X152669Y1364014D02*
X146669D01*
Y1352014D01*
X152669D01*
Y1364014D01*
G01X172385Y1346640D02*
Y1382336D01*
X154669D01*
Y1346640D01*
X172385D01*
G01X163227Y1385175D02*
Y1387601D01*
G01X152189Y1392826D02*
X155389D01*
G01X152189Y1399026D02*
Y1392826D01*
G01X155389Y1399026D02*
X152189D01*
G01X155389Y1392826D02*
Y1399026D01*
G01X146890Y1409378D02*
Y1406178D01*
G01X153090D02*
Y1409378D01*
G01X146890Y1406178D02*
X153090D01*
G01Y1409378D02*
X146890D01*
G01X148162Y1547609D02*
Y1544409D01*
G01X154362Y1547609D02*
X148162D01*
G01X154362Y1544409D02*
Y1547609D01*
G01X148162Y1544409D02*
X154362D01*
G01X146756Y1596555D02*
Y1598262D01*
G01Y1602252D02*
Y1604266D01*
G01X156700Y1715982D02*
Y1722182D01*
X153500D01*
Y1715982D01*
X156700D01*
G01X166286Y392795D02*
Y398995D01*
G01X163086Y392795D02*
X166286D01*
G01X163086Y398995D02*
Y392795D01*
G01Y389645D02*
X166286D01*
G01X163086Y395845D02*
Y389645D01*
G01X166286Y395845D02*
X163086D01*
G01X166286Y389645D02*
Y395845D01*
G01X166962Y392903D02*
X170162D01*
G01X166962Y399103D02*
Y392903D01*
G01X170162D02*
Y399103D01*
G01X166286Y398995D02*
X163086D01*
G01X170162Y399103D02*
X166962D01*
G01X160797Y1232596D02*
Y1238796D01*
G01X175465Y1238726D02*
Y1244926D01*
G01X172265Y1238726D02*
X175465D01*
G01X172265Y1244926D02*
Y1238726D01*
G01X163799Y1258564D02*
Y1255364D01*
G01X169999Y1258564D02*
X163799D01*
G01X169999Y1255364D02*
Y1258564D01*
G01X163799Y1255364D02*
X169999D01*
G01X175465Y1244926D02*
X172265D01*
G01X169899Y1259964D02*
Y1271964D01*
G01X163899Y1259964D02*
X169899D01*
G01X163899Y1271964D02*
Y1259964D01*
G01X169899Y1271964D02*
X163899D01*
G01X162204Y1340472D02*
X164444D01*
G01X163231Y1338847D02*
Y1342097D01*
G01X180239Y1364014D02*
X174239D01*
Y1352014D01*
X180239D01*
Y1364014D01*
G01X165058Y1397998D02*
Y1385998D01*
G01X171058D02*
Y1397998D01*
G01X165058Y1385998D02*
X171058D01*
G01X173464Y1397998D02*
Y1385998D01*
G01D02*
X179464D01*
G01X171058Y1397998D02*
X165058D01*
G01X179464D02*
X173464D01*
G01X186543Y1406115D02*
Y1412115D01*
X174543D01*
Y1406115D01*
X186543D01*
G01X196620Y682662D02*
X190420D01*
Y679462D01*
X196620D01*
Y682662D01*
G01X190002Y757765D02*
X193202D01*
G01X190002Y763965D02*
Y757765D01*
G01X193202Y763965D02*
X190002D01*
G01X186002Y757765D02*
X189202D01*
G01X186002Y763965D02*
Y757765D01*
G01X189202Y763965D02*
X186002D01*
G01X189202Y757765D02*
Y763965D01*
G01X182002Y757765D02*
X185202D01*
G01X182002Y763965D02*
Y757765D01*
G01X185202Y763965D02*
X182002D01*
G01X185202Y757765D02*
Y763965D01*
G01X177499Y1258564D02*
Y1255364D01*
G01X183699Y1258564D02*
X177499D01*
G01X183699Y1255364D02*
Y1258564D01*
G01X177499Y1255364D02*
X183699D01*
G01X190854Y1254343D02*
Y1257543D01*
G01X184654Y1254343D02*
X190854D01*
G01X184654Y1257543D02*
Y1254343D01*
G01X190854Y1257543D02*
X184654D01*
G01X183599Y1259964D02*
Y1271964D01*
G01X177599Y1259964D02*
X183599D01*
G01X177599Y1271964D02*
Y1259964D01*
G01X183599Y1271964D02*
X177599D01*
G01X191215Y1364014D02*
X185215D01*
Y1352014D01*
X191215D01*
Y1364014D01*
G01X184327Y1354101D02*
Y1360301D01*
X181127D01*
Y1354101D01*
X184327D01*
G01X179464Y1385998D02*
Y1397998D01*
G01X188732Y1392801D02*
X191932D01*
G01X188732Y1399001D02*
Y1392801D01*
G01X191932Y1399001D02*
X188732D01*
G01X192571Y1412270D02*
X189371D01*
G01Y1406070D02*
X192571D01*
G01X189371Y1412270D02*
Y1406070D01*
G01X204579Y-507370D02*
X205379Y-508036D01*
X206279Y-508436D01*
X207079D01*
X207879Y-508036D01*
X208479Y-507370D01*
X208779Y-506436D01*
X208579Y-505503D01*
X208079Y-504703D01*
X207179Y-504169D01*
X205979Y-503903D01*
X205279Y-503369D01*
X204979Y-502436D01*
X205179Y-501503D01*
X205679Y-500836D01*
X206379Y-500436D01*
X207079D01*
X207779Y-500703D01*
X208379Y-501369D01*
G01X213479Y-500436D02*
X215879D01*
G01X214679D02*
Y-508436D01*
G01X213479D02*
X215879D01*
G01X220679Y-500436D02*
Y-508436D01*
X224679D01*
G01X228479D02*
Y-500436D01*
G01X232279D02*
X228479Y-505370D01*
G01X232879Y-508436D02*
X230179Y-503103D01*
G01X237379Y-505769D02*
X239979D01*
G01X247479Y-504169D02*
X247879Y-503769D01*
X248179Y-503103D01*
X248379Y-502169D01*
X248179Y-501369D01*
X247779Y-500836D01*
X247079Y-500436D01*
X244379D01*
Y-508436D01*
X247679D01*
X248379Y-507903D01*
X248779Y-507103D01*
X248979Y-506169D01*
X248779Y-505236D01*
X248179Y-504436D01*
X247479Y-504169D01*
X244379D01*
G01X254679Y-508436D02*
X253879Y-508303D01*
X253179Y-507769D01*
X252579Y-506969D01*
X252179Y-506036D01*
X251979Y-504969D01*
Y-503903D01*
X252179Y-502836D01*
X252579Y-501903D01*
X253179Y-501103D01*
X253879Y-500569D01*
X254679Y-500436D01*
X255479Y-500569D01*
X256179Y-501103D01*
X256779Y-501903D01*
X257179Y-502836D01*
X257379Y-503903D01*
Y-504969D01*
X257179Y-506036D01*
X256779Y-506969D01*
X256179Y-507769D01*
X255479Y-508303D01*
X254679Y-508436D01*
G01X262679Y-500436D02*
Y-508436D01*
G01X260379Y-500436D02*
X264979D01*
G01X199650Y-473979D02*
Y-481979D01*
X203650D01*
G01X211450D02*
Y-476646D01*
G01Y-477579D02*
X211050Y-477046D01*
X210450Y-476779D01*
X209750Y-476646D01*
X209050Y-476912D01*
X208450Y-477446D01*
X208050Y-478246D01*
X207850Y-479312D01*
X208050Y-480379D01*
X208450Y-481179D01*
X209050Y-481712D01*
X209750Y-481979D01*
X210450Y-481846D01*
X211050Y-481446D01*
X211450Y-480913D01*
G01X215550Y-484379D02*
X216150Y-484646D01*
X216950Y-484379D01*
X217450Y-483846D01*
X217850Y-483179D01*
X218450Y-481046D01*
X219750Y-476646D01*
G01X216550D02*
X218450Y-481046D01*
G01X224150Y-478379D02*
X227350D01*
X227050Y-477446D01*
X226550Y-476912D01*
X225850Y-476646D01*
X225150Y-476779D01*
X224550Y-477179D01*
X224150Y-478112D01*
X223950Y-478913D01*
Y-479712D01*
X224150Y-480512D01*
X224650Y-481312D01*
X225250Y-481846D01*
X225950Y-481979D01*
X226650Y-481712D01*
X227350Y-480913D01*
G01X232250Y-481979D02*
Y-476646D01*
G01Y-477712D02*
X232750Y-477179D01*
X233250Y-476779D01*
X233950Y-476646D01*
X234450Y-476779D01*
X235050Y-477179D01*
G01X201440Y564382D02*
X207640D01*
G01X201440Y567582D02*
Y564382D01*
G01X207640Y567582D02*
X201440D01*
G01X207640Y564382D02*
Y567582D01*
G01X203036Y599201D02*
X209236D01*
G01X203036Y602401D02*
Y599201D01*
G01X209236Y602401D02*
X203036D01*
G01X202946Y633282D02*
X209146D01*
G01X202946Y636482D02*
Y633282D01*
G01X209146Y636482D02*
X202946D01*
G01X203720Y672262D02*
X206920D01*
G01X203720Y678462D02*
Y672262D01*
G01X206920D02*
Y678462D01*
G01X202960Y668142D02*
Y674342D01*
G01X199760Y668142D02*
X202960D01*
G01X199760Y674342D02*
Y668142D01*
G01X207620Y672262D02*
X210820D01*
G01X207620Y678462D02*
Y672262D01*
G01X206920Y678462D02*
X203720D01*
G01X202960Y674342D02*
X199760D01*
G01X210820Y678462D02*
X207620D01*
G01X203038Y695226D02*
X215038D01*
G01X203038Y701226D02*
Y695226D01*
G01X215038Y701226D02*
X203038D01*
G01X206002Y757765D02*
X209202D01*
G01X206002Y763965D02*
Y757765D01*
G01X209202Y763965D02*
X206002D01*
G01X202002Y757765D02*
X205202D01*
G01X202002Y763965D02*
Y757765D01*
G01X205202Y763965D02*
X202002D01*
G01X205202Y757765D02*
Y763965D01*
G01X194002Y757765D02*
X197202D01*
G01X194002Y763965D02*
Y757765D01*
G01X197202Y763965D02*
X194002D01*
G01X197202Y757765D02*
Y763965D01*
G01X198002Y757765D02*
X201202D01*
G01X198002Y763965D02*
Y757765D01*
G01X201202Y763965D02*
X198002D01*
G01X201202Y757765D02*
Y763965D01*
G01X193202Y757765D02*
Y763965D01*
G01X207199Y1258564D02*
Y1255364D01*
G01X213399Y1258564D02*
X207199D01*
G01Y1255364D02*
X213399D01*
G01X193499Y1258564D02*
Y1255364D01*
G01X199699Y1258564D02*
X193499D01*
G01X199699Y1255364D02*
Y1258564D01*
G01X193499Y1255364D02*
X199699D01*
G01X207319Y1243336D02*
X213519D01*
G01X207319Y1246536D02*
Y1243336D01*
G01X213519Y1246536D02*
X207319D01*
G01X207299Y1259964D02*
X213299D01*
G01X207299Y1271964D02*
Y1259964D01*
G01X213299Y1271964D02*
X207299D01*
G01X199599Y1259964D02*
Y1271964D01*
G01X193599Y1259964D02*
X199599D01*
G01X193599Y1271964D02*
Y1259964D01*
G01X199599Y1271964D02*
X193599D01*
G01X200604Y1340472D02*
X202844D01*
G01X201631Y1338847D02*
Y1342097D01*
G01X210785Y1346640D02*
Y1382336D01*
X193069D01*
Y1346640D01*
X210785D01*
G01X203201Y1397998D02*
Y1385998D01*
G01D02*
X209201D01*
G01X201627Y1385175D02*
Y1387601D01*
G01X209201Y1397998D02*
X203201D01*
G01X191932Y1392801D02*
Y1399001D01*
G01X192571Y1406070D02*
Y1412270D01*
G01X223350Y-531979D02*
Y-523979D01*
X227950Y-531979D01*
Y-523979D01*
G01X233650Y-526646D02*
Y-531979D01*
G01Y-524512D02*
X233450Y-524379D01*
Y-524112D01*
X233650Y-523979D01*
X233850Y-524112D01*
Y-524379D01*
X233650Y-524512D01*
G01X239950Y-531979D02*
Y-526646D01*
G01Y-527979D02*
X240350Y-527312D01*
X240950Y-526779D01*
X241750Y-526646D01*
X242450Y-526779D01*
X243050Y-527312D01*
X243350Y-528246D01*
Y-531979D01*
G01X251450D02*
Y-526646D01*
G01Y-527579D02*
X251050Y-527046D01*
X250450Y-526779D01*
X249750Y-526646D01*
X249050Y-526912D01*
X248450Y-527446D01*
X248050Y-528246D01*
X247850Y-529312D01*
X248050Y-530379D01*
X248450Y-531179D01*
X249050Y-531712D01*
X249750Y-531979D01*
X250450Y-531846D01*
X251050Y-531446D01*
X251450Y-530913D01*
G01X222643Y578422D02*
X220217D01*
G01X215354Y571019D02*
Y574219D01*
G01X209154Y571019D02*
X215354D01*
G01X209154Y574219D02*
Y571019D01*
G01X215354Y574219D02*
X209154D01*
G01X210063Y583471D02*
X222063D01*
G01X210063Y589471D02*
Y583471D01*
G01X222063Y589471D02*
X210063D01*
G01X222063Y583471D02*
Y589471D01*
G01X210063Y591877D02*
X222063D01*
G01X210063Y597877D02*
Y591877D01*
G01X222063Y597877D02*
X210063D01*
G01X222063Y591877D02*
Y597877D01*
G01X222153Y612172D02*
X219727D01*
G01X215354Y605019D02*
Y608219D01*
G01X209154Y605019D02*
X215354D01*
G01X209154Y608219D02*
Y605019D01*
G01X209236Y599201D02*
Y602401D01*
G01X210063Y617471D02*
X222063D01*
G01X210063Y623471D02*
Y617471D01*
G01X222063Y623471D02*
X210063D01*
G01X222063Y617471D02*
Y623471D01*
G01X215354Y608219D02*
X209154D01*
G01X210063Y625877D02*
X222063D01*
G01X210063Y631877D02*
Y625877D01*
G01X222063Y631877D02*
X210063D01*
G01X222063Y625877D02*
Y631877D01*
G01X221573Y645432D02*
X219147D01*
G01X215354Y639019D02*
Y642219D01*
G01X209154Y639019D02*
X215354D01*
G01X209154Y642219D02*
Y639019D01*
G01X209146Y633282D02*
Y636482D01*
G01X210063Y651471D02*
X222063D01*
G01X210063Y657471D02*
Y651471D01*
G01X222063D02*
Y657471D01*
G01X215354Y642219D02*
X209154D01*
G01X210063Y659877D02*
X222063D01*
G01X210063Y665877D02*
Y659877D01*
G01X222063Y665877D02*
X210063D01*
G01X222063Y659877D02*
Y665877D01*
G01Y657471D02*
X210063D01*
G01X210820Y672262D02*
Y678462D01*
G01X215859Y685339D02*
X213433D01*
G01X218698Y694497D02*
Y676781D01*
G01D02*
X254394D01*
G01X215038Y695226D02*
Y701226D01*
G01X254394Y694497D02*
X218698D01*
G01X209202Y757765D02*
Y763965D01*
G01X210002Y757765D02*
X213202D01*
G01X210002Y763965D02*
Y757765D01*
G01X213202Y763965D02*
X210002D01*
G01X213202Y757765D02*
Y763965D01*
G01X220872Y764485D02*
X217672D01*
G01X220872Y758285D02*
Y764485D01*
G01X217672Y758285D02*
X220872D01*
G01X217672Y764485D02*
Y758285D01*
G01X223448Y1009428D02*
X229448D01*
G01X223448Y1021428D02*
Y1009428D01*
G01X229448Y1021428D02*
X223448D01*
G01X213399Y1255364D02*
Y1258564D01*
G01X222999Y1259120D02*
Y1255920D01*
G01D02*
X229199D01*
G01X220738Y1254344D02*
Y1257544D01*
G01X214538Y1254344D02*
X220738D01*
G01X214538Y1257544D02*
Y1254344D01*
G01X220738Y1257544D02*
X214538D01*
G01X213519Y1243336D02*
Y1246536D01*
G01X223299Y1259964D02*
X229299D01*
G01X223299Y1271964D02*
Y1259964D01*
G01X229299Y1271964D02*
X223299D01*
G01X213299Y1259964D02*
Y1271964D01*
G01X229199Y1259120D02*
X222999D01*
G01X222980Y1362891D02*
X216980D01*
Y1350891D01*
X222980D01*
Y1362891D01*
G01X216180Y1354094D02*
Y1360294D01*
X212980D01*
Y1354094D01*
X216180D01*
G01X209201Y1385998D02*
Y1397998D01*
G01X211607D02*
Y1385998D01*
G01X217607D02*
Y1397998D01*
G01X211607Y1385998D02*
X217607D01*
G01Y1397998D02*
X211607D01*
G01X215613Y1406935D02*
X227613D01*
G01X215613Y1412935D02*
Y1406935D01*
G01X227613Y1412935D02*
X215613D01*
G01X214174Y1617677D02*
X246660D01*
G01X214174Y1624292D02*
Y1617677D01*
G01Y1642922D02*
Y1628572D01*
G01Y1710292D02*
Y1649282D01*
G01Y1781456D02*
Y1718202D01*
G01X304331Y1781456D02*
X214174D01*
G01X236463Y29653D02*
X239663D01*
G01X236463Y35853D02*
Y29653D01*
G01X239663Y35853D02*
X236463D01*
G01X239663Y29653D02*
Y35853D01*
G01X224745Y573590D02*
X260485D01*
G01X224745Y590520D02*
Y573590D01*
G01X260485Y590520D02*
X224745D01*
G01Y607590D02*
X260485D01*
G01X224745Y624520D02*
Y607590D01*
G01X260485Y624520D02*
X224745D01*
G01Y641590D02*
X260485D01*
G01X224745Y658520D02*
Y641590D01*
G01X238018Y668881D02*
X250018D01*
G01X238018Y674881D02*
Y668881D01*
G01X260485Y658520D02*
X224745D01*
G01X250018Y674881D02*
X238018D01*
G01X247978Y702357D02*
X235978D01*
G01Y696357D02*
X247978D01*
G01X235978Y702357D02*
Y696357D01*
G01X239777Y703225D02*
X245977D01*
G01X239777Y706425D02*
Y703225D01*
G01X245977Y706425D02*
X239777D01*
G01X237072Y993274D02*
Y981274D01*
G01D02*
X243072D01*
G01Y993274D02*
X237072D01*
G01X236658Y1011586D02*
X242658D01*
G01X236658Y1023586D02*
Y1011586D01*
G01X229448Y1009428D02*
Y1021428D01*
G01X242658Y1023586D02*
X236658D01*
G01X230980Y1240683D02*
Y1243883D01*
G01X224780Y1240683D02*
X230980D01*
G01X224780Y1243883D02*
Y1240683D01*
G01X236767Y1259056D02*
Y1255856D01*
G01D02*
X242967D01*
G01X239560Y1249592D02*
Y1243392D01*
G01D02*
X242760D01*
G01Y1249592D02*
X239560D01*
G01X229199Y1255920D02*
Y1259120D01*
G01X230980Y1243883D02*
X224780D01*
G01X236999Y1259964D02*
X242999D01*
G01X236999Y1271964D02*
Y1259964D01*
G01X242999Y1271964D02*
X236999D01*
G01X229299Y1259964D02*
Y1271964D01*
G01X242967Y1259056D02*
X236767D01*
G01X227613Y1406935D02*
Y1412935D01*
G01X239608Y1640341D02*
X239378Y1640651D01*
X239110Y1640806D01*
X238803Y1640858D01*
X238420Y1640755D01*
X238152Y1640496D01*
X238075Y1640186D01*
X238113Y1639876D01*
X238267Y1639618D01*
X239033Y1639101D01*
X239378Y1638740D01*
X239608Y1638223D01*
X239685Y1637758D01*
X238075D01*
G01X231006Y1637825D02*
Y1640925D01*
X231466Y1640305D01*
G01Y1637825D02*
X230546D01*
G01X226476Y1644368D02*
Y1641268D01*
G01X227358Y1644368D02*
X225594D01*
G01X227281Y1646405D02*
X226974Y1646147D01*
X226629Y1645992D01*
X226323D01*
X226016Y1646147D01*
X225786Y1646405D01*
X225671Y1646767D01*
X225748Y1647129D01*
X225939Y1647439D01*
X226284Y1647645D01*
X226744Y1647749D01*
X227013Y1647955D01*
X227128Y1648317D01*
X227051Y1648679D01*
X226859Y1648937D01*
X226591Y1649092D01*
X226323D01*
X226054Y1648989D01*
X225824Y1648730D01*
G01X227203Y1661756D02*
Y1664856D01*
X226283D01*
X225976Y1664701D01*
X225746Y1664339D01*
X225669Y1663926D01*
X225746Y1663513D01*
X225938Y1663203D01*
X226283Y1663048D01*
X227203D01*
G01X226356Y1657641D02*
X226663Y1657693D01*
X226931Y1657899D01*
X227161Y1658209D01*
X227314Y1658571D01*
X227391Y1658984D01*
Y1659398D01*
X227314Y1659811D01*
X227161Y1660173D01*
X226931Y1660483D01*
X226663Y1660689D01*
X226356Y1660741D01*
X226049Y1660689D01*
X225781Y1660483D01*
X225551Y1660173D01*
X225398Y1659811D01*
X225321Y1659398D01*
Y1658984D01*
X225398Y1658571D01*
X225551Y1658209D01*
X225781Y1657899D01*
X226049Y1657693D01*
X226356Y1657641D01*
G01X226049Y1658468D02*
X225589Y1657641D01*
G01X227123Y1652917D02*
Y1656017D01*
X226164D01*
X225858Y1655862D01*
X225666Y1655655D01*
X225589Y1655242D01*
X225666Y1654829D01*
X225896Y1654570D01*
X226164Y1654415D01*
X227123D01*
G01X226164D02*
X225589Y1652917D01*
G01X227318Y1671204D02*
Y1674304D01*
X225554Y1671204D01*
Y1674304D01*
G01X226436Y1666480D02*
X226743Y1666532D01*
X227011Y1666738D01*
X227241Y1667048D01*
X227394Y1667410D01*
X227471Y1667823D01*
Y1668237D01*
X227394Y1668650D01*
X227241Y1669012D01*
X227011Y1669322D01*
X226743Y1669528D01*
X226436Y1669580D01*
X226129Y1669528D01*
X225861Y1669322D01*
X225631Y1669012D01*
X225478Y1668650D01*
X225401Y1668237D01*
Y1667823D01*
X225478Y1667410D01*
X225631Y1667048D01*
X225861Y1666738D01*
X226129Y1666532D01*
X226436Y1666480D01*
G01X227203Y1683753D02*
Y1680653D01*
X225669D01*
G01X227433Y1675929D02*
Y1679029D01*
X226436Y1676446D01*
X225439Y1679029D01*
Y1675929D01*
G01X226896Y1697926D02*
X225976D01*
G01X226436D02*
Y1694826D01*
G01X226896D02*
X225976D01*
G01X227203Y1690722D02*
X227011Y1690412D01*
X226781Y1690205D01*
X226513Y1690102D01*
X226206Y1690205D01*
X225976Y1690412D01*
X225746Y1690722D01*
X225669Y1691135D01*
Y1693202D01*
G01X227279Y1685378D02*
Y1688478D01*
G01X225823D02*
X227279Y1686566D01*
G01X225593Y1685378D02*
X226628Y1687445D01*
G01X226206Y1705825D02*
X225439D01*
Y1704895D01*
X225669Y1704585D01*
X225938Y1704378D01*
X226321Y1704275D01*
X226704Y1704378D01*
X226973Y1704585D01*
X227203Y1704895D01*
X227356Y1705257D01*
X227433Y1705670D01*
Y1706032D01*
X227356Y1706342D01*
X227203Y1706703D01*
X226973Y1707013D01*
X226743Y1707220D01*
X226436Y1707375D01*
X226168D01*
X225861Y1707272D01*
X225631Y1707065D01*
G01X227241Y1699551D02*
Y1702651D01*
G01X225631D02*
Y1699551D01*
G01Y1701101D02*
X227241D01*
G01X225669Y1713724D02*
X227203D01*
Y1716824D01*
X225669D01*
G01X226283Y1715326D02*
X227203D01*
G01X227164Y1709000D02*
Y1712100D01*
X225708D01*
G01X226244Y1710602D02*
X227164D01*
G01X227279Y1718448D02*
Y1721548D01*
X226513D01*
X226206Y1721393D01*
X225976Y1721186D01*
X225784Y1720876D01*
X225631Y1720515D01*
X225593Y1719998D01*
X225631Y1719481D01*
X225784Y1719120D01*
X225976Y1718810D01*
X226206Y1718603D01*
X226513Y1718448D01*
X227279D01*
G01X225593Y1726015D02*
X225823Y1726170D01*
X226091Y1726273D01*
X226398D01*
X226743Y1726118D01*
X227011Y1725860D01*
X227203Y1725550D01*
X227356Y1725033D01*
X227394Y1724568D01*
X227318Y1724103D01*
X227203Y1723793D01*
X226973Y1723483D01*
X226704Y1723276D01*
X226436Y1723173D01*
X226168D01*
X225899Y1723276D01*
X225669Y1723431D01*
X225478Y1723638D01*
G01X226129Y1729550D02*
X225976Y1729705D01*
X225861Y1729964D01*
X225784Y1730325D01*
X225861Y1730635D01*
X226014Y1730842D01*
X226283Y1730997D01*
X227318D01*
Y1727897D01*
X226053D01*
X225784Y1728104D01*
X225631Y1728414D01*
X225554Y1728775D01*
X225631Y1729137D01*
X225861Y1729447D01*
X226129Y1729550D01*
X227318D01*
G01X227394Y1732622D02*
X226436Y1735722D01*
X225478Y1732622D01*
G01X225823Y1733707D02*
X227049D01*
G01X255722Y38470D02*
X252522D01*
G01X255722Y32270D02*
Y38470D01*
G01X252522Y32270D02*
X255722D01*
G01X252522Y38470D02*
Y32270D01*
G01X247820Y38462D02*
X244620D01*
G01X247820Y32262D02*
Y38462D01*
G01X244620Y32262D02*
X247820D01*
G01X244620Y38462D02*
Y32262D01*
G01X251820Y38462D02*
X248620D01*
G01X251820Y32262D02*
Y38462D01*
G01X248620Y32262D02*
X251820D01*
G01X248620Y38462D02*
Y32262D01*
G01X243820Y38462D02*
X240620D01*
G01X243820Y32262D02*
Y38462D01*
G01X240620Y32262D02*
X243820D01*
G01X240620Y38462D02*
Y32262D01*
G01X253465Y67636D02*
X265465D01*
G01X253465Y73636D02*
Y67636D01*
G01X248459Y65186D02*
X245259D01*
G01X248459Y58986D02*
Y65186D01*
G01X245259Y58986D02*
X248459D01*
G01X245259Y65186D02*
Y58986D01*
G01X249259Y58996D02*
X252459D01*
G01X249259Y65196D02*
Y58996D01*
G01X252459Y65196D02*
X249259D01*
G01X252459Y58996D02*
Y65196D01*
G01X265465Y73636D02*
X253465D01*
G01X265169Y81930D02*
X253169D01*
G01Y75930D02*
X265169D01*
G01X253169Y81930D02*
Y75930D01*
G01X254018Y571690D02*
X242018D01*
G01X254018Y565690D02*
Y571690D01*
G01X242018Y565690D02*
X254018D01*
G01X242018Y571690D02*
Y565690D01*
G01X254018Y605690D02*
X242018D01*
G01X254018Y599690D02*
Y605690D01*
G01X242018Y599690D02*
X254018D01*
G01X242018Y605690D02*
Y599690D01*
G01X254018Y598420D02*
X242018D01*
G01X254018Y592420D02*
Y598420D01*
G01X242018Y592420D02*
X254018D01*
G01X242018Y598420D02*
Y592420D01*
G01X254018Y639690D02*
X242018D01*
G01X254018Y633690D02*
Y639690D01*
G01X242018Y633690D02*
X254018D01*
G01X242018Y639690D02*
Y633690D01*
G01X254018Y632420D02*
X242018D01*
G01X254018Y626420D02*
Y632420D01*
G01X242018Y626420D02*
X254018D01*
G01X242018Y632420D02*
Y626420D01*
G01X250018Y668881D02*
Y674881D01*
G01X252718Y666720D02*
X240718D01*
G01X252718Y660720D02*
Y666720D01*
G01X240718Y660720D02*
X252718D01*
G01X240718Y666720D02*
Y660720D01*
G01X260562Y684316D02*
Y686556D01*
G01X262187Y685343D02*
X258937D01*
G01X254394Y676781D02*
Y694497D01*
G01X247978Y696357D02*
Y702357D01*
G01X245977Y703225D02*
Y706425D01*
G01X246842Y767807D02*
X250042D01*
G01X246842Y774007D02*
Y767807D01*
G01X250042D02*
Y774007D01*
G01X255742Y767107D02*
X258942D01*
G01X255742Y773307D02*
Y767107D01*
G01X252057Y762685D02*
X248857D01*
G01X252057Y756485D02*
Y762685D01*
G01X248857Y756485D02*
X252057D01*
G01X248857Y762685D02*
Y756485D01*
G01X256077Y762795D02*
X252877D01*
G01X256077Y756595D02*
Y762795D01*
G01X252877Y756595D02*
X256077D01*
G01X252877Y762795D02*
Y756595D01*
G01X250042Y774007D02*
X246842D01*
G01X258942Y773307D02*
X255742D01*
G01X253172Y993374D02*
Y981374D01*
G01D02*
X259172D01*
G01X243072Y981274D02*
Y993274D01*
G01X259172Y993374D02*
X253172D01*
G01X252528Y1011609D02*
X258528D01*
G01X252528Y1023609D02*
Y1011609D01*
G01X251102Y1011579D02*
Y1023579D01*
G01X245102Y1011579D02*
X251102D01*
G01X245102Y1023579D02*
Y1011579D01*
G01X242658Y1011586D02*
Y1023586D01*
G01X258528Y1023609D02*
X252528D01*
G01X251102Y1023579D02*
X245102D01*
G01X242967Y1255856D02*
Y1259056D01*
G01X252767Y1257356D02*
Y1254156D01*
G01X258967Y1257356D02*
X252767D01*
G01Y1254156D02*
X258967D01*
G01X252767Y1253164D02*
Y1249964D01*
G01X258967Y1253164D02*
X252767D01*
G01Y1249964D02*
X258967D01*
G01X243466Y1252781D02*
X246666D01*
G01X243466Y1258981D02*
Y1252781D01*
G01X246666D02*
Y1258981D01*
G01X242760Y1243392D02*
Y1249592D01*
G01X242999Y1259964D02*
Y1271964D01*
G01X252999Y1259964D02*
X258999D01*
G01X252999Y1271964D02*
Y1259964D01*
G01X258999Y1271964D02*
X252999D01*
G01X246666Y1258981D02*
X243466D01*
G01X252980Y1617677D02*
X271780D01*
G01X254168Y1637758D02*
Y1640858D01*
X255586Y1638636D01*
X253670D01*
G01X247597Y1638445D02*
X247367Y1638083D01*
X247061Y1637877D01*
X246716Y1637825D01*
X246409Y1637877D01*
X246102Y1638135D01*
X245911Y1638445D01*
X245872Y1638755D01*
X245949Y1639117D01*
X246217Y1639375D01*
X246486Y1639478D01*
X246831D01*
G01X246486D02*
X246256Y1639633D01*
X246064Y1639892D01*
X245987Y1640202D01*
X246064Y1640512D01*
X246256Y1640770D01*
X246601Y1640925D01*
X246946Y1640873D01*
X247291Y1640667D01*
G01X263536Y54560D02*
Y57760D01*
G01X257336Y54560D02*
X263536D01*
G01X257336Y57760D02*
Y54560D01*
G01X265465Y67636D02*
Y73636D01*
G01X263581Y62855D02*
Y66055D01*
G01X257381Y62855D02*
X263581D01*
G01X257381Y66055D02*
Y62855D01*
G01X263581Y66055D02*
X257381D01*
G01X263533Y58745D02*
Y61945D01*
G01X257333Y58745D02*
X263533D01*
G01X257333Y61945D02*
Y58745D01*
G01X263533Y61945D02*
X257333D01*
G01X263536Y57760D02*
X257336D01*
G01X265169Y75930D02*
Y81930D01*
G01X269953Y201603D02*
Y204703D01*
G01X268343D02*
Y201603D01*
G01Y203153D02*
X269953D01*
G01X266891Y202223D02*
X266661Y201861D01*
X266355Y201655D01*
X266010Y201603D01*
X265703Y201655D01*
X265396Y201913D01*
X265205Y202223D01*
X265166Y202533D01*
X265243Y202895D01*
X265511Y203153D01*
X265780Y203256D01*
X266125D01*
G01X265780D02*
X265550Y203411D01*
X265358Y203670D01*
X265281Y203980D01*
X265358Y204290D01*
X265550Y204548D01*
X265895Y204703D01*
X266240Y204651D01*
X266585Y204445D01*
G01X262948Y201603D02*
Y204703D01*
X263408Y204083D01*
G01Y201603D02*
X262488D01*
G01X260485Y573590D02*
Y590520D01*
G01X261635Y573589D02*
X260126Y573593D01*
G01X261685Y590522D02*
X261679Y573539D01*
G01X261085Y590522D02*
X261089Y573547D01*
G01X260485Y590522D02*
X260488Y573582D01*
G01X265310Y582507D02*
X263070D01*
G01X264283Y584132D02*
Y580882D01*
G01X261685Y590522D02*
X260485D01*
G01Y607590D02*
Y624520D01*
G01X261635Y607589D02*
X260126Y607593D01*
G01X261685Y624522D02*
X261679Y607539D01*
G01X261085Y624522D02*
X261089Y607547D01*
G01X260485Y624522D02*
X260488Y607582D01*
G01X265310Y616507D02*
X263070D01*
G01X264283Y618132D02*
Y614882D01*
G01X261685Y624522D02*
X260485D01*
G01X265310Y650507D02*
X263070D01*
G01X264283Y652132D02*
Y648882D01*
G01X260485Y641590D02*
Y658520D01*
G01X261635Y641589D02*
X260126Y641593D01*
G01X261685Y658522D02*
X261679Y641539D01*
G01X261085Y658522D02*
X261089Y641547D01*
G01X260485Y658522D02*
X260488Y641582D01*
G01X261685Y658522D02*
X260485D01*
G01X267446Y718569D02*
X270646D01*
G01X267446Y724769D02*
Y718569D01*
G01X270646D02*
Y724769D01*
G01X271446Y718569D02*
X274646D01*
G01X271446Y724769D02*
Y718569D01*
G01X263443D02*
X266643D01*
G01X263443Y724769D02*
Y718569D01*
G01X266643D02*
Y724769D01*
G01X267446Y728364D02*
X270646D01*
G01X267446Y734564D02*
Y728364D01*
G01X270646Y734564D02*
X267446D01*
G01X270646Y728364D02*
Y734564D01*
G01Y724769D02*
X267446D01*
G01X274646D02*
X271446D01*
G01X274646Y734564D02*
X271446D01*
G01Y728364D02*
X274646D01*
G01X271446Y734564D02*
Y728364D01*
G01X266643Y724769D02*
X263443D01*
G01X271400Y738904D02*
X274600D01*
G01X271400Y745104D02*
Y738904D01*
G01X274600Y745104D02*
X271400D01*
G01X274846Y754264D02*
X271646D01*
G01Y748064D02*
X274846D01*
G01X271646Y754264D02*
Y748064D01*
G01X267270Y742468D02*
X270470D01*
G01X267270Y748668D02*
Y742468D01*
G01X270470Y748668D02*
X267270D01*
G01X270470Y742468D02*
Y748668D01*
G01X258942Y767107D02*
Y773307D01*
G01X257166Y959653D02*
Y956453D01*
G01X263366Y959653D02*
X257166D01*
G01X263366Y956453D02*
Y959653D01*
G01X257166Y956453D02*
X263366D01*
G01X259172Y981374D02*
Y993374D01*
G01X258528Y1011609D02*
Y1023609D01*
G01X267370Y1248361D02*
X269610D01*
G01X268397Y1246736D02*
Y1249986D01*
G01X268597Y1260548D02*
X270566Y1258580D01*
G01X266628D02*
X268597Y1260548D01*
G01X270566Y1258580D02*
X266628D01*
G01X265841Y1251711D02*
X271353D01*
G01X265841Y1267859D02*
Y1251711D01*
G01X271353D02*
Y1267859D01*
G01X276293Y1256586D02*
X273093D01*
G01Y1250386D02*
X276293D01*
G01X273093Y1256586D02*
Y1250386D01*
G01X258967Y1254156D02*
Y1257356D01*
G01Y1249964D02*
Y1253164D01*
G01X258999Y1259964D02*
Y1271964D01*
G01X275763Y1275112D02*
Y1278212D01*
X274997D01*
X274690Y1278057D01*
X274460Y1277850D01*
X274268Y1277540D01*
X274115Y1277179D01*
X274077Y1276662D01*
X274115Y1276145D01*
X274268Y1275784D01*
X274460Y1275474D01*
X274690Y1275267D01*
X274997Y1275112D01*
X275763D01*
G01X271360D02*
Y1278212D01*
X272778Y1275990D01*
X270862D01*
G01X269448Y1276404D02*
X269180Y1276765D01*
X268950Y1276972D01*
X268643Y1277075D01*
X268375Y1276972D01*
X268183Y1276765D01*
X268030Y1276455D01*
X267992Y1276094D01*
X268030Y1275784D01*
X268183Y1275474D01*
X268413Y1275215D01*
X268682Y1275112D01*
X268988Y1275215D01*
X269257Y1275525D01*
X269410Y1275990D01*
X269448Y1276507D01*
X269372Y1277179D01*
X269257Y1277540D01*
X269065Y1277902D01*
X268797Y1278160D01*
X268528Y1278212D01*
X268260Y1278109D01*
X268068Y1277850D01*
G01X268547Y1273474D02*
Y1271048D01*
G01X270566Y1260942D02*
X266628D01*
G01X265847Y1269011D02*
Y1268511D01*
G01X271347Y1269011D02*
X265847D01*
G01X271347Y1268261D02*
Y1269011D01*
G01X266097Y1268261D02*
X271347D01*
G01X266097Y1267861D02*
Y1268261D01*
G01X265847Y1267861D02*
X266097D01*
G01X265847Y1268561D02*
Y1267861D01*
G01X271347Y1268561D02*
X265847D01*
G01X271347Y1267911D02*
Y1268561D01*
G01X271247Y1267911D02*
X271347D01*
G01X271353Y1267859D02*
X265841D01*
G01X271104Y1639050D02*
X270836Y1639411D01*
X270606Y1639618D01*
X270299Y1639721D01*
X270031Y1639618D01*
X269839Y1639411D01*
X269686Y1639101D01*
X269648Y1638740D01*
X269686Y1638430D01*
X269839Y1638120D01*
X270069Y1637861D01*
X270338Y1637758D01*
X270644Y1637861D01*
X270913Y1638171D01*
X271066Y1638636D01*
X271104Y1639153D01*
X271028Y1639825D01*
X270913Y1640186D01*
X270721Y1640548D01*
X270453Y1640806D01*
X270184Y1640858D01*
X269916Y1640755D01*
X269724Y1640496D01*
G01X263345Y1638290D02*
X263115Y1638032D01*
X262847Y1637877D01*
X262502Y1637825D01*
X262157Y1637928D01*
X261889Y1638135D01*
X261697Y1638497D01*
X261659Y1638910D01*
X261735Y1639323D01*
X261927Y1639582D01*
X262195Y1639788D01*
X262464Y1639840D01*
X262732Y1639788D01*
X263077Y1639582D01*
X262962Y1640925D01*
X261927D01*
G01X289120Y41262D02*
X292320D01*
G01X289120Y47462D02*
Y41262D01*
G01X292320Y47462D02*
X289120D01*
G01X288320D02*
X285120D01*
G01X288320Y41262D02*
Y47462D01*
G01X285120Y41262D02*
X288320D01*
G01X285120Y47462D02*
Y41262D01*
G01X278646Y718569D02*
Y724769D01*
G01X275446Y718569D02*
X278646D01*
G01X275446Y724769D02*
Y718569D01*
G01X284446D02*
X287646D01*
G01X284446Y724769D02*
Y718569D01*
G01X287646D02*
Y724769D01*
G01X280520Y718467D02*
X283720D01*
G01X280520Y724667D02*
Y718467D01*
G01X283720D02*
Y724667D01*
G01X292553Y718925D02*
X289353D01*
G01Y712725D02*
X292553D01*
G01X289353Y718925D02*
Y712725D01*
G01X274646Y718569D02*
Y724769D01*
G01X282646Y734564D02*
X279446D01*
G01X282646Y728364D02*
Y734564D01*
G01X279446Y728364D02*
X282646D01*
G01X279446Y734564D02*
Y728364D01*
G01X278646Y724769D02*
X275446D01*
G01X287646D02*
X284446D01*
G01X283720Y724667D02*
X280520D01*
G01X278646Y734564D02*
X275446D01*
G01X278646Y728364D02*
Y734564D01*
G01X275446Y728364D02*
X278646D01*
G01X275446Y734564D02*
Y728364D01*
G01X274646D02*
Y734564D01*
G01X287046Y747764D02*
X290246D01*
G01X287046Y753964D02*
Y747764D01*
G01X290246Y753964D02*
X287046D01*
G01X274600Y738904D02*
Y745104D01*
G01X278646Y745064D02*
X275446D01*
G01X278646Y738864D02*
Y745064D01*
G01X275446Y738864D02*
X278646D01*
G01X275446Y745064D02*
Y738864D01*
G01X282646Y745064D02*
X279446D01*
G01X282646Y738864D02*
Y745064D01*
G01X279446Y738864D02*
X282646D01*
G01X279446Y745064D02*
Y738864D01*
G01X286646Y745064D02*
X283446D01*
G01X286646Y738864D02*
Y745064D01*
G01X283446Y738864D02*
X286646D01*
G01X283446Y745064D02*
Y738864D01*
G01X274846Y748064D02*
Y754264D01*
G01X282646Y754064D02*
X279446D01*
G01X282646Y747864D02*
Y754064D01*
G01X279446Y747864D02*
X282646D01*
G01X279446Y754064D02*
Y747864D01*
G01X278646Y754064D02*
X275446D01*
G01X278646Y747864D02*
Y754064D01*
G01X275446Y747864D02*
X278646D01*
G01X275446Y754064D02*
Y747864D01*
G01X286646Y754064D02*
X283446D01*
G01X286646Y747864D02*
Y754064D01*
G01X283446Y747864D02*
X286646D01*
G01X283446Y754064D02*
Y747864D01*
G01X277239Y862347D02*
Y868547D01*
G01X274039Y862347D02*
X277239D01*
G01X274039Y868547D02*
Y862347D01*
G01X277239Y868547D02*
X274039D01*
G01X276293Y1250386D02*
Y1256586D01*
G01X295957Y1528567D02*
Y1531667D01*
X294960Y1529084D01*
X293963Y1531667D01*
Y1528567D01*
G01X291093D02*
X292627D01*
Y1531667D01*
X291093D01*
G01X291707Y1530169D02*
X292627D01*
G01X289412Y1528929D02*
X289143Y1528670D01*
X288837Y1528567D01*
X288530Y1528670D01*
X288262Y1528980D01*
X288070Y1529445D01*
X287993Y1529910D01*
Y1530479D01*
X288070Y1530944D01*
X288262Y1531357D01*
X288492Y1531564D01*
X288760Y1531667D01*
X289067Y1531564D01*
X289297Y1531357D01*
X289450Y1531047D01*
X289527Y1530634D01*
X289450Y1530272D01*
X289258Y1529910D01*
X289028Y1529704D01*
X288760Y1529652D01*
X288453Y1529755D01*
X288223Y1530014D01*
X287993Y1530479D01*
G01X289290Y1617677D02*
X304331D01*
G01X278480D02*
X284920D01*
G01X278327Y1637825D02*
X278250Y1638497D01*
X278135Y1639065D01*
X277982Y1639582D01*
X277790Y1640150D01*
X277483Y1640925D01*
X279017D01*
G01X286124Y1637758D02*
X285856Y1637810D01*
X285549Y1637965D01*
X285357Y1638223D01*
X285281Y1638585D01*
X285357Y1638946D01*
X285587Y1639256D01*
X285932Y1639411D01*
X286316D01*
X286546Y1639515D01*
X286737Y1639773D01*
X286814Y1640135D01*
X286699Y1640496D01*
X286431Y1640755D01*
X286124Y1640858D01*
X285817Y1640755D01*
X285549Y1640496D01*
X285434Y1640135D01*
X285511Y1639773D01*
X285702Y1639515D01*
X285932Y1639411D01*
X286316D01*
X286661Y1639256D01*
X286891Y1638946D01*
X286967Y1638585D01*
X286891Y1638223D01*
X286699Y1637965D01*
X286392Y1637810D01*
X286124Y1637758D01*
G01X371260Y1646023D02*
X281103D01*
G01D02*
Y1781456D01*
G01D02*
X371260D01*
G01X293920Y13637D02*
X297120D01*
G01X293920Y19837D02*
Y13637D01*
G01X297120Y19837D02*
X293920D01*
G01X297120Y13637D02*
Y19837D01*
G01X293120D02*
X289920D01*
G01X293120Y13637D02*
Y19837D01*
G01X289920Y13637D02*
X293120D01*
G01X289920Y19837D02*
Y13637D01*
G01X304320Y47462D02*
X301120D01*
G01X304320Y41262D02*
Y47462D01*
G01X301120Y41262D02*
X304320D01*
G01X301120Y47462D02*
Y41262D01*
G01X297120D02*
X300320D01*
G01X297120Y47462D02*
Y41262D01*
G01X300320Y47462D02*
X297120D01*
G01X300320Y41262D02*
Y47462D01*
G01X296320D02*
X293120D01*
G01X296320Y41262D02*
Y47462D01*
G01X293120Y41262D02*
X296320D01*
G01X293120Y47462D02*
Y41262D01*
G01X305120D02*
X308320D01*
G01X305120Y47462D02*
Y41262D01*
G01X308320Y47462D02*
X305120D01*
G01X292320Y41262D02*
Y47462D01*
G01X299811Y182379D02*
X296611D01*
G01X299811Y176179D02*
Y182379D01*
G01X296611Y176179D02*
X299811D01*
G01X296611Y182379D02*
Y176179D01*
G01X300611Y175679D02*
X306811D01*
G01X300611Y178879D02*
Y175679D01*
G01X306811Y178879D02*
X300611D01*
G01Y179679D02*
X306811D01*
G01X300611Y182879D02*
Y179679D01*
G01X306811Y182879D02*
X300611D01*
G01X293087Y702970D02*
X296287D01*
G01X293087Y709170D02*
Y702970D01*
G01X296287D02*
Y709170D01*
G01X299438Y719224D02*
X302638D01*
G01X299438Y725424D02*
Y719224D01*
G01X302638D02*
Y725424D01*
G01X292553Y712725D02*
Y718925D01*
G01X299438Y712085D02*
X302638D01*
G01X299438Y718285D02*
Y712085D01*
G01X302638Y718285D02*
X299438D01*
G01X302638Y712085D02*
Y718285D01*
G01X296287Y709170D02*
X293087D01*
G01X295487Y722317D02*
X298687D01*
G01X295487Y728517D02*
Y722317D01*
G01X298687Y728517D02*
X295487D01*
G01X298687Y722317D02*
Y728517D01*
G01X302638Y725424D02*
X299438D01*
G01X303002Y728894D02*
X306202D01*
G01X303002Y735094D02*
Y728894D01*
G01X306202Y735094D02*
X303002D01*
G01X290246Y747764D02*
Y753964D01*
G01X294306Y753908D02*
X291106D01*
G01X294306Y747708D02*
Y753908D01*
G01X291106Y747708D02*
X294306D01*
G01X291106Y753908D02*
Y747708D01*
G01X295106D02*
X298306D01*
G01X295106Y753908D02*
Y747708D01*
G01X298306Y753908D02*
X295106D01*
G01X298306Y747708D02*
Y753908D01*
G01X316722Y991220D02*
G03I-9950J0D01*
G01X302439Y1306456D02*
Y1312656D01*
G01X299239Y1306456D02*
X302439D01*
G01X299239Y1312656D02*
Y1306456D01*
G01Y1314091D02*
X302439D01*
G01X299239Y1320291D02*
Y1314091D01*
G01X302439Y1320291D02*
X299239D01*
G01X302439Y1314091D02*
Y1320291D01*
G01Y1312656D02*
X299239D01*
G01X304607Y1350947D02*
X307807D01*
G01X304607Y1357147D02*
Y1350947D01*
G01X300801Y1358436D02*
X304001D01*
G01X300801Y1364636D02*
Y1358436D01*
G01X304001Y1364636D02*
X300801D01*
G01X304001Y1358436D02*
Y1364636D01*
G01X307807Y1357147D02*
X304607D01*
G01X370037Y1625562D02*
Y1633062D01*
X367797D01*
X367050Y1632687D01*
X366490Y1631812D01*
X366303Y1630812D01*
X366490Y1629812D01*
X366957Y1629062D01*
X367797Y1628687D01*
X370037D01*
G01X362537Y1625562D02*
Y1633062D01*
X360203D01*
X359457Y1632687D01*
X358990Y1632187D01*
X358803Y1631187D01*
X358990Y1630187D01*
X359550Y1629562D01*
X360203Y1629187D01*
X362537D01*
G01X360203D02*
X358803Y1625562D01*
G01X351303D02*
X355037D01*
Y1633062D01*
X351303D01*
G01X352797Y1629437D02*
X355037D01*
G01X347630Y1626562D02*
X346883Y1625937D01*
X346043Y1625562D01*
X345297D01*
X344550Y1625937D01*
X343990Y1626562D01*
X343710Y1627437D01*
X343897Y1628312D01*
X344363Y1629062D01*
X345203Y1629562D01*
X346323Y1629812D01*
X346977Y1630312D01*
X347257Y1631187D01*
X347070Y1632062D01*
X346603Y1632687D01*
X345950Y1633062D01*
X345297D01*
X344643Y1632812D01*
X344083Y1632187D01*
G01X340130Y1626562D02*
X339383Y1625937D01*
X338543Y1625562D01*
X337797D01*
X337050Y1625937D01*
X336490Y1626562D01*
X336210Y1627437D01*
X336397Y1628312D01*
X336863Y1629062D01*
X337703Y1629562D01*
X338823Y1629812D01*
X339477Y1630312D01*
X339757Y1631187D01*
X339570Y1632062D01*
X339103Y1632687D01*
X338450Y1633062D01*
X337797D01*
X337143Y1632812D01*
X336583Y1632187D01*
G01X331883Y1628062D02*
X329457D01*
G01X324943Y1625562D02*
Y1633062D01*
X321397D01*
G01X322703Y1629437D02*
X324943D01*
G01X316790Y1633062D02*
X314550D01*
G01X315670D02*
Y1625562D01*
G01X316790D02*
X314550D01*
G01X308170Y1633062D02*
Y1625562D01*
G01X310317Y1633062D02*
X306023D01*
G01X304331Y1617677D02*
Y1663980D01*
G01X370187Y1651542D02*
Y1659042D01*
X367947D01*
X367200Y1658667D01*
X366640Y1657792D01*
X366453Y1656792D01*
X366640Y1655792D01*
X367107Y1655042D01*
X367947Y1654667D01*
X370187D01*
G01X362687Y1651542D02*
Y1659042D01*
X360353D01*
X359607Y1658667D01*
X359140Y1658167D01*
X358953Y1657167D01*
X359140Y1656167D01*
X359700Y1655542D01*
X360353Y1655167D01*
X362687D01*
G01X360353D02*
X358953Y1651542D01*
G01X351453D02*
X355187D01*
Y1659042D01*
X351453D01*
G01X352947Y1655417D02*
X355187D01*
G01X347780Y1652542D02*
X347033Y1651917D01*
X346193Y1651542D01*
X345447D01*
X344700Y1651917D01*
X344140Y1652542D01*
X343860Y1653417D01*
X344047Y1654292D01*
X344513Y1655042D01*
X345353Y1655542D01*
X346473Y1655792D01*
X347127Y1656292D01*
X347407Y1657167D01*
X347220Y1658042D01*
X346753Y1658667D01*
X346100Y1659042D01*
X345447D01*
X344793Y1658792D01*
X344233Y1658167D01*
G01X340280Y1652542D02*
X339533Y1651917D01*
X338693Y1651542D01*
X337947D01*
X337200Y1651917D01*
X336640Y1652542D01*
X336360Y1653417D01*
X336547Y1654292D01*
X337013Y1655042D01*
X337853Y1655542D01*
X338973Y1655792D01*
X339627Y1656292D01*
X339907Y1657167D01*
X339720Y1658042D01*
X339253Y1658667D01*
X338600Y1659042D01*
X337947D01*
X337293Y1658792D01*
X336733Y1658167D01*
G01X332033Y1654042D02*
X329607D01*
G01X325093Y1651542D02*
Y1659042D01*
X321547D01*
G01X322853Y1655417D02*
X325093D01*
G01X316940Y1659042D02*
X314700D01*
G01X315820D02*
Y1651542D01*
G01X316940D02*
X314700D01*
G01X308320Y1659042D02*
Y1651542D01*
G01X310467Y1659042D02*
X306173D01*
G01X298118Y1665802D02*
Y1668902D01*
X298578Y1668282D01*
G01Y1665802D02*
X297658D01*
G01X306720Y1668385D02*
X306490Y1668695D01*
X306222Y1668850D01*
X305915Y1668902D01*
X305532Y1668799D01*
X305264Y1668540D01*
X305187Y1668230D01*
X305225Y1667920D01*
X305379Y1667662D01*
X306145Y1667145D01*
X306490Y1666784D01*
X306720Y1666267D01*
X306797Y1665802D01*
X305187D01*
G01X293522Y1682283D02*
Y1679183D01*
X291988D01*
G01X293752Y1674459D02*
Y1677559D01*
X292755Y1674976D01*
X291758Y1677559D01*
Y1674459D01*
G01X293637Y1669735D02*
Y1672835D01*
X291873Y1669735D01*
Y1672835D01*
G01X293215Y1696457D02*
X292295D01*
G01X292755D02*
Y1693357D01*
G01X293215D02*
X292295D01*
G01X293522Y1689252D02*
X293330Y1688942D01*
X293100Y1688735D01*
X292832Y1688632D01*
X292525Y1688735D01*
X292295Y1688942D01*
X292065Y1689252D01*
X291988Y1689665D01*
Y1691732D01*
G01X293598Y1683908D02*
Y1687008D01*
G01X292142D02*
X293598Y1685096D01*
G01X291912Y1683908D02*
X292947Y1685975D01*
G01X293554Y1697652D02*
Y1700752D01*
G01X291944D02*
Y1697652D01*
G01Y1699202D02*
X293554D01*
G01X291988Y1712254D02*
X293522D01*
Y1715354D01*
X291988D01*
G01X292602Y1713856D02*
X293522D01*
G01X293483Y1707530D02*
Y1710630D01*
X292027D01*
G01X292563Y1709132D02*
X293483D01*
G01X292419Y1704002D02*
X291652D01*
Y1703072D01*
X291882Y1702762D01*
X292151Y1702555D01*
X292534Y1702452D01*
X292917Y1702555D01*
X293186Y1702762D01*
X293416Y1703072D01*
X293569Y1703434D01*
X293646Y1703847D01*
Y1704209D01*
X293569Y1704519D01*
X293416Y1704880D01*
X293186Y1705190D01*
X292956Y1705397D01*
X292649Y1705552D01*
X292381D01*
X292074Y1705449D01*
X291844Y1705242D01*
G01X292448Y1728081D02*
X292295Y1728236D01*
X292180Y1728495D01*
X292103Y1728856D01*
X292180Y1729166D01*
X292333Y1729373D01*
X292602Y1729528D01*
X293637D01*
Y1726428D01*
X292372D01*
X292103Y1726635D01*
X291950Y1726945D01*
X291873Y1727306D01*
X291950Y1727668D01*
X292180Y1727978D01*
X292448Y1728081D01*
X293637D01*
G01X291912Y1724545D02*
X292142Y1724700D01*
X292410Y1724803D01*
X292717D01*
X293062Y1724648D01*
X293330Y1724390D01*
X293522Y1724080D01*
X293675Y1723563D01*
X293713Y1723098D01*
X293637Y1722633D01*
X293522Y1722323D01*
X293292Y1722013D01*
X293023Y1721806D01*
X292755Y1721703D01*
X292487D01*
X292218Y1721806D01*
X291988Y1721961D01*
X291797Y1722168D01*
G01X293598Y1716979D02*
Y1720079D01*
X292832D01*
X292525Y1719924D01*
X292295Y1719717D01*
X292103Y1719407D01*
X291950Y1719046D01*
X291912Y1718529D01*
X291950Y1718012D01*
X292103Y1717651D01*
X292295Y1717341D01*
X292525Y1717134D01*
X292832Y1716979D01*
X293598D01*
G01X304331Y1738150D02*
Y1781456D01*
G01X293507Y1731652D02*
X292549Y1734752D01*
X291591Y1731652D01*
G01X291936Y1732737D02*
X293162D01*
G01X308320Y41262D02*
Y47462D01*
G01X327461Y164359D02*
Y196159D01*
X313661D01*
Y164359D01*
X327461D01*
G01X306811Y175679D02*
Y178879D01*
G01Y179679D02*
Y182879D01*
G01X318745Y203449D02*
X324945D01*
G01X318745Y206649D02*
Y203449D01*
G01X324945Y206649D02*
X318745D01*
G01X317945Y209724D02*
X314745D01*
G01X317945Y203524D02*
Y209724D01*
G01X314745Y203524D02*
X317945D01*
G01X314745Y209724D02*
Y203524D01*
G01X319758Y233087D02*
X316558D01*
G01X319758Y226887D02*
Y233087D01*
G01X316558Y226887D02*
X319758D01*
G01X316558Y233087D02*
Y226887D01*
G01X319056Y721688D02*
X322256D01*
G01X319056Y727888D02*
Y721688D01*
G01X315056D02*
X318256D01*
G01X315056Y727888D02*
Y721688D01*
G01X318256D02*
Y727888D01*
G01X314256Y721688D02*
Y727888D01*
G01X311056Y721688D02*
X314256D01*
G01X311056Y727888D02*
Y721688D01*
G01X309567Y721744D02*
Y727944D01*
G01X306367Y721744D02*
X309567D01*
G01X306367Y727944D02*
Y721744D01*
G01X322256Y727888D02*
X319056D01*
G01X318256Y734888D02*
X315056D01*
G01X318256Y728688D02*
Y734888D01*
G01X315056Y728688D02*
X318256D01*
G01X315056Y734888D02*
Y728688D01*
G01X306202Y728894D02*
Y735094D01*
G01X322256Y734888D02*
X319056D01*
G01Y728688D02*
X322256D01*
G01X319056Y734888D02*
Y728688D01*
G01X318256Y727888D02*
X315056D01*
G01X314256D02*
X311056D01*
G01X309567Y727944D02*
X306367D01*
G01X319567Y748215D02*
Y754415D01*
G01X316367Y748215D02*
X319567D01*
G01X316367Y754415D02*
Y748215D01*
G01Y739234D02*
X319567D01*
G01X316367Y745434D02*
Y739234D01*
G01X319567Y745434D02*
X316367D01*
G01X319567Y739234D02*
Y745434D01*
G01Y754415D02*
X316367D01*
G01X318581Y1299470D02*
X324581D01*
G01X318581Y1311470D02*
Y1299470D01*
G01X317318Y1299498D02*
Y1311498D01*
G01X311318Y1299498D02*
X317318D01*
G01X311318Y1311498D02*
Y1299498D01*
G01X324581Y1311470D02*
X318581D01*
G01X317318Y1311498D02*
X311318D01*
G01X319041Y1356144D02*
Y1344144D01*
G01X325041Y1356144D02*
X319041D01*
G01Y1344144D02*
X325041D01*
G01X307807Y1350947D02*
Y1357147D01*
G01X320544Y1359387D02*
X326544D01*
G01X320544Y1371387D02*
Y1359387D01*
G01X326544Y1371387D02*
X320544D01*
G01X314709Y1666422D02*
X314479Y1666060D01*
X314173Y1665854D01*
X313828Y1665802D01*
X313521Y1665854D01*
X313214Y1666112D01*
X313023Y1666422D01*
X312984Y1666732D01*
X313061Y1667094D01*
X313329Y1667352D01*
X313598Y1667455D01*
X313943D01*
G01X313598D02*
X313368Y1667610D01*
X313176Y1667869D01*
X313099Y1668179D01*
X313176Y1668489D01*
X313368Y1668747D01*
X313713Y1668902D01*
X314058Y1668850D01*
X314403Y1668644D01*
G01X321280Y1665802D02*
Y1668902D01*
X322698Y1666680D01*
X320782D01*
G01X326250Y-525312D02*
X326850Y-524512D01*
X327550Y-524112D01*
X328350Y-523979D01*
X329350Y-524246D01*
X330050Y-524912D01*
X330250Y-525712D01*
X330150Y-526513D01*
X329750Y-527179D01*
X327750Y-528512D01*
X326850Y-529446D01*
X326250Y-530779D01*
X326050Y-531979D01*
X330250D01*
G01X336150Y-523979D02*
X335350Y-524246D01*
X334750Y-524912D01*
X334350Y-525712D01*
X334050Y-526779D01*
X333950Y-527979D01*
X334050Y-529179D01*
X334350Y-530246D01*
X334750Y-531046D01*
X335350Y-531712D01*
X336150Y-531979D01*
X336950Y-531712D01*
X337550Y-531046D01*
X337950Y-530246D01*
X338250Y-529179D01*
X338350Y-527979D01*
X338250Y-526779D01*
X337950Y-525712D01*
X337550Y-524912D01*
X336950Y-524246D01*
X336150Y-523979D01*
G01X342250Y-525312D02*
X342850Y-524512D01*
X343550Y-524112D01*
X344350Y-523979D01*
X345350Y-524246D01*
X346050Y-524912D01*
X346250Y-525712D01*
X346150Y-526513D01*
X345750Y-527179D01*
X343750Y-528512D01*
X342850Y-529446D01*
X342250Y-530779D01*
X342050Y-531979D01*
X346250D01*
G01X349950Y-530379D02*
X350550Y-531312D01*
X351350Y-531846D01*
X352250Y-531979D01*
X353050Y-531846D01*
X353850Y-531179D01*
X354350Y-530379D01*
X354450Y-529579D01*
X354250Y-528646D01*
X353550Y-527979D01*
X352850Y-527712D01*
X351950D01*
G01X352850D02*
X353450Y-527312D01*
X353950Y-526646D01*
X354150Y-525846D01*
X353950Y-525046D01*
X353450Y-524379D01*
X352550Y-523979D01*
X351650Y-524112D01*
X350750Y-524646D01*
G01X358350Y-532246D02*
X361950Y-523979D01*
G01X368150D02*
X367350Y-524246D01*
X366750Y-524912D01*
X366350Y-525712D01*
X366050Y-526779D01*
X365950Y-527979D01*
X366050Y-529179D01*
X366350Y-530246D01*
X366750Y-531046D01*
X367350Y-531712D01*
X368150Y-531979D01*
X368950Y-531712D01*
X369550Y-531046D01*
X369950Y-530246D01*
X370250Y-529179D01*
X370350Y-527979D01*
X370250Y-526779D01*
X369950Y-525712D01*
X369550Y-524912D01*
X368950Y-524246D01*
X368150Y-523979D01*
G01X373950Y-530379D02*
X374550Y-531312D01*
X375350Y-531846D01*
X376250Y-531979D01*
X377050Y-531846D01*
X377850Y-531179D01*
X378350Y-530379D01*
X378450Y-529579D01*
X378250Y-528646D01*
X377550Y-527979D01*
X376850Y-527712D01*
X375950D01*
G01X376850D02*
X377450Y-527312D01*
X377950Y-526646D01*
X378150Y-525846D01*
X377950Y-525046D01*
X377450Y-524379D01*
X376550Y-523979D01*
X375650Y-524112D01*
X374750Y-524646D01*
G01X382350Y-532246D02*
X385950Y-523979D01*
G01X390250Y-525312D02*
X390850Y-524512D01*
X391550Y-524112D01*
X392350Y-523979D01*
X393350Y-524246D01*
X394050Y-524912D01*
X394250Y-525712D01*
X394150Y-526513D01*
X393750Y-527179D01*
X391750Y-528512D01*
X390850Y-529446D01*
X390250Y-530779D01*
X390050Y-531979D01*
X394250D01*
G01X401350D02*
Y-523979D01*
X397650Y-529712D01*
X402650D01*
G01X325950Y-506979D02*
Y-498979D01*
X327950D01*
X328750Y-499379D01*
X329350Y-499912D01*
X329850Y-500712D01*
X330250Y-501646D01*
X330350Y-502979D01*
X330250Y-504312D01*
X329850Y-505246D01*
X329350Y-506046D01*
X328750Y-506579D01*
X327950Y-506979D01*
X325950D01*
G01X333650D02*
X336150Y-498979D01*
X338650Y-506979D01*
G01X337750Y-504179D02*
X334550D01*
G01X344150Y-498979D02*
X343350Y-499246D01*
X342750Y-499912D01*
X342350Y-500712D01*
X342050Y-501779D01*
X341950Y-502979D01*
X342050Y-504179D01*
X342350Y-505246D01*
X342750Y-506046D01*
X343350Y-506712D01*
X344150Y-506979D01*
X344950Y-506712D01*
X345550Y-506046D01*
X345950Y-505246D01*
X346250Y-504179D01*
X346350Y-502979D01*
X346250Y-501779D01*
X345950Y-500712D01*
X345550Y-499912D01*
X344950Y-499246D01*
X344150Y-498979D01*
G01X350250Y-506979D02*
Y-498979D01*
X354050D01*
G01X352650Y-502846D02*
X350250D01*
G01X360150Y-498979D02*
X359350Y-499246D01*
X358750Y-499912D01*
X358350Y-500712D01*
X358050Y-501779D01*
X357950Y-502979D01*
X358050Y-504179D01*
X358350Y-505246D01*
X358750Y-506046D01*
X359350Y-506712D01*
X360150Y-506979D01*
X360950Y-506712D01*
X361550Y-506046D01*
X361950Y-505246D01*
X362250Y-504179D01*
X362350Y-502979D01*
X362250Y-501779D01*
X361950Y-500712D01*
X361550Y-499912D01*
X360950Y-499246D01*
X360150Y-498979D01*
G01X368150D02*
Y-506979D01*
G01X365850Y-498979D02*
X370450D01*
G01X373550Y-506979D02*
Y-498979D01*
X376150Y-505646D01*
X378750Y-498979D01*
Y-506979D01*
G01X384950Y-502712D02*
X385350Y-502312D01*
X385650Y-501646D01*
X385850Y-500712D01*
X385650Y-499912D01*
X385250Y-499379D01*
X384550Y-498979D01*
X381850D01*
Y-506979D01*
X385150D01*
X385850Y-506446D01*
X386250Y-505646D01*
X386450Y-504712D01*
X386250Y-503779D01*
X385650Y-502979D01*
X384950Y-502712D01*
X381850D01*
G01X390950Y-498979D02*
X393350D01*
G01X392150D02*
Y-506979D01*
G01X390950D02*
X393350D01*
G01X398150Y-505379D02*
X398650Y-506179D01*
X399250Y-506712D01*
X399950Y-506979D01*
X400750Y-506712D01*
X401350Y-506179D01*
X401950Y-505379D01*
X402150Y-504312D01*
Y-498979D01*
G01X408150D02*
X407350Y-499246D01*
X406750Y-499912D01*
X406350Y-500712D01*
X406050Y-501779D01*
X405950Y-502979D01*
X406050Y-504179D01*
X406350Y-505246D01*
X406750Y-506046D01*
X407350Y-506712D01*
X408150Y-506979D01*
X408950Y-506712D01*
X409550Y-506046D01*
X409950Y-505246D01*
X410250Y-504179D01*
X410350Y-502979D01*
X410250Y-501779D01*
X409950Y-500712D01*
X409550Y-499912D01*
X408950Y-499246D01*
X408150Y-498979D01*
G01X326125Y206649D02*
Y203449D01*
G01X332325Y206649D02*
X326125D01*
G01X332325Y203449D02*
Y206649D01*
G01X326125Y203449D02*
X332325D01*
G01X324945D02*
Y206649D01*
G01X336561Y713690D02*
X339761D01*
G01X336561Y719890D02*
Y713690D01*
G01X339761Y719890D02*
X336561D01*
G01X327056Y721688D02*
X330256D01*
G01X327056Y727888D02*
Y721688D01*
G01X330256D02*
Y727888D01*
G01X322256Y721688D02*
Y727888D01*
G01X334256Y721688D02*
Y727888D01*
G01X331056Y721688D02*
X334256D01*
G01X331056Y727888D02*
Y721688D01*
G01X326256D02*
Y727888D01*
G01X323056Y721688D02*
X326256D01*
G01X323056Y727888D02*
Y721688D01*
G01X325496Y737198D02*
X328696D01*
G01X325496Y743398D02*
Y737198D01*
G01X328696D02*
Y743398D01*
G01X336146Y737198D02*
Y743398D01*
G01X332946Y737198D02*
X336146D01*
G01X332946Y743398D02*
Y737198D01*
G01X330256Y727888D02*
X327056D01*
G01X333526Y729198D02*
X336726D01*
G01X333526Y735398D02*
Y729198D01*
G01X336726Y735398D02*
X333526D01*
G01X336726Y729198D02*
Y735398D01*
G01X322256Y728688D02*
Y734888D01*
G01X334256Y727888D02*
X331056D01*
G01X326256D02*
X323056D01*
G01X328696Y743398D02*
X325496D01*
G01X334846Y747708D02*
X338046D01*
G01X334846Y753908D02*
Y747708D01*
G01X338046Y753908D02*
X334846D01*
G01X338046Y747708D02*
Y753908D01*
G01X336146Y743398D02*
X332946D01*
G01X332988Y1286512D02*
X338988D01*
G01X332988Y1298512D02*
Y1286512D01*
G01X338988Y1298512D02*
X332988D01*
G01X324581Y1299470D02*
Y1311470D01*
G01X327020Y1303452D02*
X330220D01*
G01X327020Y1309652D02*
Y1303452D01*
G01X330220D02*
Y1309652D01*
G01D02*
X327020D01*
G01X336700Y1328149D02*
X339900D01*
G01X336700Y1334349D02*
Y1328149D01*
G01X339900Y1334349D02*
X336700D01*
G01X334579Y1335418D02*
X337779D01*
G01X334579Y1341618D02*
Y1335418D01*
G01X337779D02*
Y1341618D01*
G01X327447Y1356144D02*
Y1344144D01*
G01X333447Y1356144D02*
X327447D01*
G01X333447Y1344144D02*
Y1356144D01*
G01X327447Y1344144D02*
X333447D01*
G01X325041D02*
Y1356144D01*
G01X337779Y1341618D02*
X334579D01*
G01X326544Y1359387D02*
Y1371387D01*
G01X338216Y1667094D02*
X337948Y1667455D01*
X337718Y1667662D01*
X337411Y1667765D01*
X337143Y1667662D01*
X336951Y1667455D01*
X336798Y1667145D01*
X336760Y1666784D01*
X336798Y1666474D01*
X336951Y1666164D01*
X337181Y1665905D01*
X337450Y1665802D01*
X337756Y1665905D01*
X338025Y1666215D01*
X338178Y1666680D01*
X338216Y1667197D01*
X338140Y1667869D01*
X338025Y1668230D01*
X337833Y1668592D01*
X337565Y1668850D01*
X337296Y1668902D01*
X337028Y1668799D01*
X336836Y1668540D01*
G01X330457Y1666267D02*
X330227Y1666009D01*
X329959Y1665854D01*
X329614Y1665802D01*
X329269Y1665905D01*
X329001Y1666112D01*
X328809Y1666474D01*
X328771Y1666887D01*
X328847Y1667300D01*
X329039Y1667559D01*
X329307Y1667765D01*
X329576Y1667817D01*
X329844Y1667765D01*
X330189Y1667559D01*
X330074Y1668902D01*
X329039D01*
G01X343750Y-481979D02*
Y-473979D01*
X347550D01*
G01X346150Y-477846D02*
X343750D01*
G01X353650Y-473979D02*
X352850Y-474246D01*
X352250Y-474912D01*
X351850Y-475712D01*
X351550Y-476779D01*
X351450Y-477979D01*
X351550Y-479179D01*
X351850Y-480246D01*
X352250Y-481046D01*
X352850Y-481712D01*
X353650Y-481979D01*
X354450Y-481712D01*
X355050Y-481046D01*
X355450Y-480246D01*
X355750Y-479179D01*
X355850Y-477979D01*
X355750Y-476779D01*
X355450Y-475712D01*
X355050Y-474912D01*
X354450Y-474246D01*
X353650Y-473979D01*
G01X361650D02*
Y-481979D01*
G01X359350Y-473979D02*
X363950D01*
G01X366650Y-484646D02*
X372650D01*
G01X375050Y-481979D02*
Y-473979D01*
X377650Y-480646D01*
X380250Y-473979D01*
Y-481979D01*
G01X386450Y-477712D02*
X386850Y-477312D01*
X387150Y-476646D01*
X387350Y-475712D01*
X387150Y-474912D01*
X386750Y-474379D01*
X386050Y-473979D01*
X383350D01*
Y-481979D01*
X386650D01*
X387350Y-481446D01*
X387750Y-480646D01*
X387950Y-479712D01*
X387750Y-478779D01*
X387150Y-477979D01*
X386450Y-477712D01*
X383350D01*
G01X390650Y-484646D02*
X396650D01*
G01X403650Y-481979D02*
X399650D01*
Y-473979D01*
X403650D01*
G01X402050Y-477846D02*
X399650D01*
G01X407050Y-481979D02*
Y-473979D01*
X409650Y-480646D01*
X412250Y-473979D01*
Y-481979D01*
G01X417650D02*
X418350Y-481846D01*
X419150Y-481446D01*
X419650Y-480779D01*
X419850Y-479846D01*
X419650Y-478913D01*
X419050Y-478112D01*
X418150Y-477712D01*
X417150D01*
X416550Y-477446D01*
X416050Y-476779D01*
X415850Y-475846D01*
X416150Y-474912D01*
X416850Y-474246D01*
X417650Y-473979D01*
X418450Y-474246D01*
X419150Y-474912D01*
X419450Y-475846D01*
X419250Y-476779D01*
X418750Y-477446D01*
X418150Y-477712D01*
X417150D01*
X416250Y-478112D01*
X415650Y-478913D01*
X415450Y-479846D01*
X415650Y-480779D01*
X416150Y-481446D01*
X416950Y-481846D01*
X417650Y-481979D01*
G01X423950Y-481046D02*
X424650Y-481712D01*
X425450Y-481979D01*
X426250Y-481712D01*
X426950Y-480913D01*
X427450Y-479712D01*
X427650Y-478512D01*
Y-477046D01*
X427450Y-475846D01*
X426950Y-474779D01*
X426350Y-474246D01*
X425650Y-473979D01*
X424850Y-474246D01*
X424250Y-474779D01*
X423850Y-475579D01*
X423650Y-476646D01*
X423850Y-477579D01*
X424350Y-478512D01*
X424950Y-479046D01*
X425650Y-479179D01*
X426450Y-478913D01*
X427050Y-478246D01*
X427650Y-477046D01*
G01X433650Y-473979D02*
X432850Y-474246D01*
X432250Y-474912D01*
X431850Y-475712D01*
X431550Y-476779D01*
X431450Y-477979D01*
X431550Y-479179D01*
X431850Y-480246D01*
X432250Y-481046D01*
X432850Y-481712D01*
X433650Y-481979D01*
X434450Y-481712D01*
X435050Y-481046D01*
X435450Y-480246D01*
X435750Y-479179D01*
X435850Y-477979D01*
X435750Y-476779D01*
X435450Y-475712D01*
X435050Y-474912D01*
X434450Y-474246D01*
X433650Y-473979D01*
G01X439450Y-481979D02*
Y-473979D01*
G01X443250D02*
X439450Y-478913D01*
G01X443850Y-481979D02*
X441150Y-476646D01*
G01X349897Y704365D02*
X356097D01*
G01X349897Y707565D02*
Y704365D01*
G01X356077Y719619D02*
X347415D01*
G01Y709125D02*
X356077D01*
G01X347415Y712472D02*
Y709125D01*
G01X349615Y714372D02*
X347415Y712472D01*
G01Y716272D02*
X349615Y714372D01*
G01X347415Y719619D02*
Y716272D01*
G01X339761Y713690D02*
Y719890D01*
G01X356097Y707565D02*
X349897D01*
G01X354346Y721375D02*
X357546D01*
G01X354346Y727575D02*
Y721375D01*
G01X353546Y721372D02*
Y727572D01*
G01X350346Y721372D02*
X353546D01*
G01X350346Y727572D02*
Y721372D01*
G01X349637Y721375D02*
Y727575D01*
G01X346437Y721375D02*
X349637D01*
G01X346437Y727575D02*
Y721375D01*
G01X357546Y727575D02*
X354346D01*
G01X353546Y727572D02*
X350346D01*
G01X349637Y727575D02*
X346437D01*
G01X338846Y747708D02*
X342046D01*
G01X338846Y753908D02*
Y747708D01*
G01X342046Y753908D02*
X338846D01*
G01X342046Y747708D02*
Y753908D01*
G01X342846Y747708D02*
X346046D01*
G01X342846Y753908D02*
Y747708D01*
G01X346046Y753908D02*
X342846D01*
G01X346046Y747708D02*
Y753908D01*
G01X342840Y746872D02*
Y740672D01*
G01D02*
X346040D01*
G01D02*
Y746872D01*
G01D02*
X342840D01*
G01X360049Y811121D02*
G03I-9950J0D01*
G01X366013Y1171318D02*
G03I-9950J0D01*
G01X348430Y1275080D02*
X350670D01*
G01X349457Y1273455D02*
Y1276705D01*
G01X338988Y1286512D02*
Y1298512D01*
G01X340895Y1281248D02*
X358611D01*
G01X340895Y1316944D02*
Y1281248D01*
G01X351169Y1333346D02*
Y1321346D01*
G01D02*
X357169D01*
G01X345400Y1318929D02*
Y1321355D01*
G01X358611Y1316944D02*
X340895D01*
G01X352672Y1336589D02*
X358672D01*
G01X352672Y1348589D02*
Y1336589D01*
G01X357169Y1333346D02*
X351169D01*
G01X339900Y1328149D02*
Y1334349D01*
G01X358672Y1348589D02*
X352672D01*
G01X345439Y1665802D02*
X345362Y1666474D01*
X345247Y1667042D01*
X345094Y1667559D01*
X344902Y1668127D01*
X344595Y1668902D01*
X346129D01*
G01X353236Y1665802D02*
X352968Y1665854D01*
X352661Y1666009D01*
X352469Y1666267D01*
X352393Y1666629D01*
X352469Y1666990D01*
X352699Y1667300D01*
X353044Y1667455D01*
X353428D01*
X353658Y1667559D01*
X353849Y1667817D01*
X353926Y1668179D01*
X353811Y1668540D01*
X353543Y1668799D01*
X353236Y1668902D01*
X352929Y1668799D01*
X352661Y1668540D01*
X352546Y1668179D01*
X352623Y1667817D01*
X352814Y1667559D01*
X353044Y1667455D01*
X353428D01*
X353773Y1667300D01*
X354003Y1666990D01*
X354079Y1666629D01*
X354003Y1666267D01*
X353811Y1666009D01*
X353504Y1665854D01*
X353236Y1665802D01*
G01X356097Y704365D02*
Y707565D01*
G01X367710Y716092D02*
X368017Y716144D01*
X368285Y716350D01*
X368515Y716660D01*
X368668Y717022D01*
X368745Y717435D01*
Y717849D01*
X368668Y718262D01*
X368515Y718624D01*
X368285Y718934D01*
X368017Y719140D01*
X367710Y719192D01*
X367403Y719140D01*
X367135Y718934D01*
X366905Y718624D01*
X366752Y718262D01*
X366675Y717849D01*
Y717435D01*
X366752Y717022D01*
X366905Y716660D01*
X367135Y716350D01*
X367403Y716144D01*
X367710Y716092D01*
G01X367403Y716919D02*
X366943Y716092D01*
G01X364610D02*
Y719192D01*
X365070Y718572D01*
G01Y716092D02*
X364150D01*
G01X362238Y717384D02*
X361970Y717745D01*
X361740Y717952D01*
X361433Y718055D01*
X361165Y717952D01*
X360973Y717745D01*
X360820Y717435D01*
X360782Y717074D01*
X360820Y716764D01*
X360973Y716454D01*
X361203Y716195D01*
X361472Y716092D01*
X361778Y716195D01*
X362047Y716505D01*
X362200Y716970D01*
X362238Y717487D01*
X362162Y718159D01*
X362047Y718520D01*
X361855Y718882D01*
X361587Y719140D01*
X361318Y719192D01*
X361050Y719089D01*
X360858Y718830D01*
G01X356077Y709125D02*
Y719619D01*
G01X357546Y721375D02*
Y727575D01*
G01X369302Y747708D02*
X372502D01*
G01X369302Y753908D02*
Y747708D01*
G01X372502Y753908D02*
X369302D01*
G01X361302Y747708D02*
X364502D01*
G01X361302Y753908D02*
Y747708D01*
G01X364502Y753908D02*
X361302D01*
G01X364502Y747708D02*
Y753908D01*
G01X357302Y747708D02*
X360502D01*
G01X357302Y753908D02*
Y747708D01*
G01X360502Y753908D02*
X357302D01*
G01X360502Y747708D02*
Y753908D01*
G01X368502D02*
X365302D01*
G01X368502Y747708D02*
Y753908D01*
G01X365302Y747708D02*
X368502D01*
G01X365302Y753908D02*
Y747708D01*
G01X366518Y1286512D02*
Y1298512D01*
G01X360518Y1286512D02*
X366518D01*
G01X360518Y1298512D02*
Y1286512D01*
G01X358611Y1281248D02*
Y1316944D01*
G01X366518Y1298512D02*
X360518D01*
G01X359575Y1333346D02*
Y1321346D01*
G01X365575D02*
Y1333346D01*
G01X359575Y1321346D02*
X365575D01*
G01X357169D02*
Y1333346D01*
G01X366791Y1320831D02*
X369991D01*
G01X366791Y1327031D02*
Y1320831D01*
G01X369991D02*
Y1327031D01*
G01X358672Y1336589D02*
Y1348589D01*
G01X365575Y1333346D02*
X359575D01*
G01X369991Y1327031D02*
X366791D01*
G01X359137Y1381865D02*
X372937D01*
G01X359137Y1413665D02*
Y1381865D01*
G01X372937Y1413665D02*
X359137D01*
G01X388063Y201603D02*
Y204703D01*
G01X386453D02*
Y201603D01*
G01Y203153D02*
X388063D01*
G01X385001Y202223D02*
X384771Y201861D01*
X384465Y201655D01*
X384120Y201603D01*
X383813Y201655D01*
X383506Y201913D01*
X383315Y202223D01*
X383276Y202533D01*
X383353Y202895D01*
X383621Y203153D01*
X383890Y203256D01*
X384235D01*
G01X383890D02*
X383660Y203411D01*
X383468Y203670D01*
X383391Y203980D01*
X383468Y204290D01*
X383660Y204548D01*
X384005Y204703D01*
X384350Y204651D01*
X384695Y204445D01*
G01X381786Y204186D02*
X381556Y204496D01*
X381288Y204651D01*
X380981Y204703D01*
X380598Y204600D01*
X380330Y204341D01*
X380253Y204031D01*
X380291Y203721D01*
X380445Y203463D01*
X381211Y202946D01*
X381556Y202585D01*
X381786Y202068D01*
X381863Y201603D01*
X380253D01*
G01X381302Y747708D02*
X384502D01*
G01X381302Y753908D02*
Y747708D01*
G01X384502Y753908D02*
X381302D01*
G01X384502Y747708D02*
Y753908D01*
G01X372502Y747708D02*
Y753908D01*
G01X377302Y747708D02*
X380502D01*
G01X377302Y753908D02*
Y747708D01*
G01X380502Y753908D02*
X377302D01*
G01X380502Y747708D02*
Y753908D01*
G01X385302Y747708D02*
X388502D01*
G01X385302Y753908D02*
Y747708D01*
G01X388502Y753908D02*
X385302D01*
G01X376502D02*
X373302D01*
G01X376502Y747708D02*
Y753908D01*
G01X373302Y747708D02*
X376502D01*
G01X373302Y753908D02*
Y747708D01*
G01X379437Y1272559D02*
Y1284559D01*
G01X373437Y1272559D02*
X379437D01*
G01X373437Y1284559D02*
Y1272559D01*
G01X381837D02*
X387837D01*
G01X381837Y1284559D02*
Y1272559D01*
G01X379437Y1284559D02*
X373437D01*
G01X387837D02*
X381837D01*
G01X384800Y1323163D02*
X390800D01*
G01X384800Y1335163D02*
Y1323163D01*
G01X383033Y1319543D02*
Y1307543D01*
G01X389033Y1319543D02*
X383033D01*
G01Y1307543D02*
X389033D01*
G01X370828Y1314823D02*
X374028D01*
G01X370828Y1321023D02*
Y1314823D01*
G01X374028Y1321023D02*
X370828D01*
G01X374028Y1314823D02*
Y1321023D01*
G01X390800Y1335163D02*
X384800D01*
G01X372937Y1381865D02*
Y1413665D01*
G01X371260Y1781456D02*
Y1646023D01*
G01X382140Y1658882D02*
X385340D01*
G01X382140Y1665082D02*
Y1658882D01*
G01X385340Y1665082D02*
X382140D01*
G01X385340Y1658882D02*
Y1665082D01*
G01X389410Y1665132D02*
X386210D01*
G01Y1658932D02*
X389410D01*
G01X386210Y1665132D02*
Y1658932D01*
G01X388502Y747708D02*
Y753908D01*
G01X394132Y830721D02*
Y826121D01*
G01X404332Y830721D02*
X394132D01*
G01Y826121D02*
X404332D01*
G01X399232D02*
Y830721D01*
G01X394132Y837142D02*
Y832542D01*
G01D02*
X404332D01*
G01X399232D02*
Y837142D01*
G01X404332D02*
X394132D01*
G01X397526Y1154520D02*
X409526D01*
G01X397526Y1160520D02*
Y1154520D01*
G01X409526Y1160520D02*
X397526D01*
G01Y1162570D02*
X409526D01*
G01X397526Y1168570D02*
Y1162570D01*
G01X409526Y1168570D02*
X397526D01*
G01X400518Y1272559D02*
Y1284559D01*
G01X394518Y1272559D02*
X400518D01*
G01X394518Y1284559D02*
Y1272559D01*
G01X387837D02*
Y1284559D01*
G01X402522Y1269530D02*
X420238D01*
G01X402522Y1305226D02*
Y1269530D01*
G01X400518Y1284559D02*
X394518D01*
G01X389220Y1276762D02*
X392420D01*
G01X389220Y1282962D02*
Y1276762D01*
G01X392420Y1282962D02*
X389220D01*
G01X392420Y1276762D02*
Y1282962D01*
G01X420238Y1305226D02*
X402522D01*
G01X391469Y1319543D02*
Y1307543D01*
G01X397469Y1319543D02*
X391469D01*
G01X397469Y1307543D02*
Y1319543D01*
G01X391469Y1307543D02*
X397469D01*
G01X390800Y1323163D02*
Y1335163D01*
G01X389033Y1307543D02*
Y1319543D01*
G01X398862Y1320492D02*
X402062D01*
G01X398862Y1326692D02*
Y1320492D01*
G01X402062D02*
Y1326692D01*
G01D02*
X398862D01*
G01X398009Y1402485D02*
Y1405685D01*
G01X391809Y1402485D02*
X398009D01*
G01X391809Y1405685D02*
Y1402485D01*
G01X401804Y1420092D02*
Y1416892D01*
G01X408004Y1420092D02*
X401804D01*
G01Y1416892D02*
X408004D01*
G01X391809Y1414591D02*
Y1411391D01*
G01X398009Y1414591D02*
X391809D01*
G01X398009Y1411391D02*
Y1414591D01*
G01X391809Y1411391D02*
X398009D01*
G01X391809Y1418091D02*
Y1414891D01*
G01X398009Y1418091D02*
X391809D01*
G01X398009Y1414891D02*
Y1418091D01*
G01X391809Y1414891D02*
X398009D01*
G01Y1406005D02*
Y1409205D01*
G01X391809Y1406005D02*
X398009D01*
G01X391809Y1409205D02*
Y1406005D01*
G01X398009Y1409205D02*
X391809D01*
G01X398009Y1405685D02*
X391809D01*
G01X393480Y1665092D02*
X390280D01*
G01X393480Y1658892D02*
Y1665092D01*
G01X390280Y1658892D02*
X393480D01*
G01X390280Y1665092D02*
Y1658892D01*
G01X389410Y1658932D02*
Y1665132D01*
G01X414650Y-534979D02*
Y-526979D01*
X413450Y-528579D01*
G01Y-534979D02*
X415850D01*
G01X420750Y-531646D02*
X421450Y-530712D01*
X422050Y-530179D01*
X422850Y-529912D01*
X423550Y-530179D01*
X424050Y-530712D01*
X424450Y-531512D01*
X424550Y-532446D01*
X424450Y-533246D01*
X424050Y-534046D01*
X423450Y-534712D01*
X422750Y-534979D01*
X421950Y-534712D01*
X421250Y-533913D01*
X420850Y-532712D01*
X420750Y-531379D01*
X420950Y-529646D01*
X421250Y-528712D01*
X421750Y-527779D01*
X422450Y-527112D01*
X423150Y-526979D01*
X423850Y-527246D01*
X424350Y-527912D01*
G01X430650Y-535246D02*
X430450Y-535112D01*
Y-534846D01*
X430650Y-534712D01*
X430850Y-534846D01*
Y-535112D01*
X430650Y-535246D01*
G01X436750Y-531646D02*
X437450Y-530712D01*
X438050Y-530179D01*
X438850Y-529912D01*
X439550Y-530179D01*
X440050Y-530712D01*
X440450Y-531512D01*
X440550Y-532446D01*
X440450Y-533246D01*
X440050Y-534046D01*
X439450Y-534712D01*
X438750Y-534979D01*
X437950Y-534712D01*
X437250Y-533913D01*
X436850Y-532712D01*
X436750Y-531379D01*
X436950Y-529646D01*
X437250Y-528712D01*
X437750Y-527779D01*
X438450Y-527112D01*
X439150Y-526979D01*
X439850Y-527246D01*
X440350Y-527912D01*
G01X419047Y543707D02*
Y546807D01*
X418050Y544224D01*
X417053Y546807D01*
Y543707D01*
G01X414183D02*
X415717D01*
Y546807D01*
X414183D01*
G01X414797Y545309D02*
X415717D01*
G01X412693Y544327D02*
X412463Y543965D01*
X412157Y543759D01*
X411812Y543707D01*
X411505Y543759D01*
X411198Y544017D01*
X411007Y544327D01*
X410968Y544637D01*
X411045Y544999D01*
X411313Y545257D01*
X411582Y545360D01*
X411927D01*
G01X411582D02*
X411352Y545515D01*
X411160Y545774D01*
X411083Y546084D01*
X411160Y546394D01*
X411352Y546652D01*
X411697Y546807D01*
X412042Y546755D01*
X412387Y546549D01*
G01X418752Y831842D02*
X430752D01*
G01X418752Y837842D02*
Y831842D01*
G01Y824536D02*
X430752D01*
G01X418752Y830536D02*
Y824536D01*
G01X430752Y830536D02*
X418752D01*
G01X417272D02*
X405272D01*
G01X417272Y824536D02*
Y830536D01*
G01X405272Y824536D02*
X417272D01*
G01X405272Y830536D02*
Y824536D01*
G01X417272Y831842D02*
Y837842D01*
G01X405272Y831842D02*
X417272D01*
G01X405272Y837842D02*
Y831842D01*
G01X404332Y826121D02*
Y830721D01*
G01Y832542D02*
Y837142D01*
G01X430752Y837842D02*
X418752D01*
G01X417272D02*
X405272D01*
G01X410261Y931098D02*
X414861D01*
G01X410261Y941298D02*
Y931098D01*
G01X414861D02*
Y941298D01*
G01X414961Y931098D02*
X419561D01*
G01X414961Y941298D02*
Y931098D01*
G01X405561D02*
X410161D01*
G01X405561Y941298D02*
Y931098D01*
G01X410161D02*
Y941298D01*
G01X409447Y930765D02*
Y927565D01*
G01X415647Y930765D02*
X409447D01*
G01X415647Y927565D02*
Y930765D01*
G01X409447Y927565D02*
X415647D01*
G01X422147Y930766D02*
X415947D01*
Y927566D01*
X422147D01*
Y930766D01*
G01X406367Y955635D02*
Y943635D01*
G01X412367D02*
Y955635D01*
G01X406367Y943635D02*
X412367D01*
G01X413247Y955585D02*
Y943585D01*
G01X419247D02*
Y955585D01*
G01X413247Y943585D02*
X419247D01*
G01X414861Y941298D02*
X410261D01*
G01X414861Y936198D02*
X410261D01*
G01X419561Y941298D02*
X414961D01*
G01X419561Y936198D02*
X414961D01*
G01X410161Y941298D02*
X405561D01*
G01X410161Y936198D02*
X405561D01*
G01X412061Y957860D02*
Y969860D01*
G01X406061Y957860D02*
X412061D01*
G01X406061Y969860D02*
Y957860D01*
G01X419061D02*
Y969860D01*
G01X413061Y957860D02*
X419061D01*
G01X413061Y969860D02*
Y957860D01*
G01X412367Y955635D02*
X406367D01*
G01X419247Y955585D02*
X413247D01*
G01X419061Y972340D02*
Y984340D01*
G01X413061Y972340D02*
X419061D01*
G01X413061Y984340D02*
Y972340D01*
G01X412061D02*
Y984340D01*
G01X406061Y972340D02*
X412061D01*
G01X406061Y984340D02*
Y972340D01*
G01X412061Y969860D02*
X406061D01*
G01X419061D02*
X413061D01*
G01X412061Y986820D02*
Y998820D01*
G01X406061Y986820D02*
X412061D01*
G01X406061Y998820D02*
Y986820D01*
G01X419061D02*
Y998820D01*
G01X413061Y986820D02*
X419061D01*
G01X413061Y998820D02*
Y986820D01*
G01X419061Y984340D02*
X413061D01*
G01X412061D02*
X406061D01*
G01X419061Y1001300D02*
Y1013300D01*
G01X413061Y1001300D02*
X419061D01*
G01X413061Y1013300D02*
Y1001300D01*
G01X419061Y1013300D02*
X413061D01*
G01X412061Y998820D02*
X406061D01*
G01X419061D02*
X413061D01*
G01X406061Y1013300D02*
Y1001300D01*
G01X412061Y1013300D02*
X406061D01*
G01X412061Y1001300D02*
Y1013300D01*
G01X406061Y1001300D02*
X412061D01*
G01X409732Y1029870D02*
X421732D01*
G01X409732Y1035870D02*
Y1029870D01*
G01X412061Y1015784D02*
Y1027784D01*
G01X406061Y1015784D02*
X412061D01*
G01X406061Y1027784D02*
Y1015784D01*
G01X412061Y1027784D02*
X406061D01*
G01X413061Y1027780D02*
Y1015780D01*
G01X419061Y1027780D02*
X413061D01*
G01X419061Y1015780D02*
Y1027780D01*
G01X413061Y1015780D02*
X419061D01*
G01X421732Y1035870D02*
X409732D01*
G01X409526Y1154520D02*
Y1160520D01*
G01X422026D02*
X410026D01*
G01Y1154520D02*
X422026D01*
G01X410026Y1160520D02*
Y1154520D01*
G01X409526Y1162570D02*
Y1168570D01*
G01X422026D02*
X410026D01*
G01Y1162570D02*
X422026D01*
G01X410026Y1168570D02*
Y1162570D01*
G01X410057Y1263362D02*
X412297D01*
G01X411084Y1261737D02*
Y1264987D01*
G01X408480Y1306979D02*
Y1309405D01*
G01X416928Y1323163D02*
X422928D01*
G01X416928Y1335163D02*
Y1323163D01*
G01X415425Y1319543D02*
Y1307543D01*
G01X421425Y1319543D02*
X415425D01*
G01Y1307543D02*
X421425D01*
G01X403556Y1315188D02*
X406756D01*
G01X403556Y1321388D02*
Y1315188D01*
G01X406756Y1321388D02*
X403556D01*
G01X406756Y1315188D02*
Y1321388D01*
G01X422928Y1335163D02*
X416928D01*
G01X415331Y1416875D02*
Y1413675D01*
G01X421531Y1416875D02*
X415331D01*
G01Y1413675D02*
X421531D01*
G01X408004Y1416892D02*
Y1420092D01*
G01X414527Y1406565D02*
X417727D01*
G01X414527Y1412765D02*
Y1406565D01*
G01X417727Y1412765D02*
X414527D01*
G01X417727Y1406565D02*
Y1412765D01*
G01X403420Y1415262D02*
Y1412062D01*
G01X409620Y1415262D02*
X403420D01*
G01X409620Y1412062D02*
Y1415262D01*
G01X403420Y1412062D02*
X409620D01*
G01X407470Y1631932D02*
Y1638332D01*
G01Y1631932D02*
X420350D01*
G01X407400Y1640104D02*
Y1646504D01*
G01X420280D02*
X407400D01*
G01Y1640104D02*
X420280D01*
G01X420350Y1638332D02*
X407470D01*
G01X430752Y831842D02*
Y837842D01*
G01Y824536D02*
Y830536D01*
G01X444232D02*
X432232D01*
G01Y824536D02*
X444232D01*
G01X432232Y830536D02*
Y824536D01*
G01X432229Y831842D02*
X444229D01*
G01X432229Y837842D02*
Y831842D01*
G01X444229Y837842D02*
X432229D01*
G01X426061Y931180D02*
Y943180D01*
G01X420061Y931180D02*
X426061D01*
G01X420061Y943180D02*
Y931180D01*
G01X419561Y931098D02*
Y941298D01*
G01X420061Y955680D02*
Y943680D01*
G01X426061D02*
Y955680D01*
G01X420061Y943680D02*
X426061D01*
G01Y943180D02*
X420061D01*
G01X426061Y957860D02*
Y969860D01*
G01X420061Y957860D02*
X426061D01*
G01X420061Y969860D02*
Y957860D01*
G01X426061Y955680D02*
X420061D01*
G01X426061Y972340D02*
Y984340D01*
G01X420061Y972340D02*
X426061D01*
G01X420061Y984340D02*
Y972340D01*
G01X426061Y969860D02*
X420061D01*
G01X426061Y986820D02*
Y998820D01*
G01X420061Y986820D02*
X426061D01*
G01X420061Y998820D02*
Y986820D01*
G01X426061Y984340D02*
X420061D01*
G01X426061Y998820D02*
X420061D01*
G01X426061Y1001300D02*
Y1013300D01*
G01X420061Y1001300D02*
X426061D01*
G01X420061Y1013300D02*
Y1001300D01*
G01X426061Y1013300D02*
X420061D01*
G01Y1027780D02*
Y1015780D01*
G01X426061Y1027780D02*
X420061D01*
G01X426061Y1015780D02*
Y1027780D01*
G01X420061Y1015780D02*
X426061D01*
G01X421732Y1029870D02*
Y1035870D01*
G01X422026Y1154520D02*
Y1160520D01*
G01X447026D02*
X435026D01*
G01Y1154520D02*
X447026D01*
G01X435026Y1160520D02*
Y1154520D01*
G01X422526D02*
X434526D01*
G01X422526Y1160520D02*
Y1154520D01*
G01X434526Y1160520D02*
X422526D01*
G01X434526Y1154520D02*
Y1160520D01*
G01X422026Y1162570D02*
Y1168570D01*
G01X422526Y1162570D02*
X434526D01*
G01X422526Y1168570D02*
Y1162570D01*
G01X434526Y1168570D02*
X422526D01*
G01X434526Y1162570D02*
Y1168570D01*
G01X447026D02*
X435026D01*
G01Y1162570D02*
X447026D01*
G01X435026Y1168570D02*
Y1162570D01*
G01X430274Y1272709D02*
X436274D01*
G01X430274Y1284709D02*
Y1272709D01*
G01X428274D02*
Y1284709D01*
G01X422274Y1272709D02*
X428274D01*
G01X422274Y1284709D02*
Y1272709D01*
G01X420238Y1269530D02*
Y1305226D01*
G01X436274Y1284709D02*
X430274D01*
G01X428274D02*
X422274D01*
G01X423831Y1319543D02*
Y1307543D01*
G01X429831Y1319543D02*
X423831D01*
G01X429831Y1307543D02*
Y1319543D01*
G01X423831Y1307543D02*
X429831D01*
G01X422928Y1323163D02*
Y1335163D01*
G01X421425Y1307543D02*
Y1319543D01*
G01X435101Y1314629D02*
X438301D01*
G01X435101Y1320829D02*
Y1314629D01*
G01X438301Y1320829D02*
X435101D01*
G01X430128Y1320467D02*
X433328D01*
G01X430128Y1326667D02*
Y1320467D01*
G01X433328D02*
Y1326667D01*
G01D02*
X430128D01*
G01X422720Y1400462D02*
X425920D01*
G01X422720Y1406662D02*
Y1400462D01*
G01X425920D02*
Y1406662D01*
G01X429310Y1400472D02*
X432510D01*
G01X429310Y1406672D02*
Y1400472D01*
G01X432510D02*
Y1406672D01*
G01X421531Y1413675D02*
Y1416875D01*
G01X433384Y1413675D02*
X439584D01*
G01X433384Y1416875D02*
Y1413675D01*
G01X439584Y1416875D02*
X433384D01*
G01X433374Y1406189D02*
X439574D01*
G01X433374Y1409389D02*
Y1406189D01*
G01X439574Y1409389D02*
X433374D01*
G01X425920Y1406662D02*
X422720D01*
G01X432510Y1406672D02*
X429310D01*
G01X431928Y1628947D02*
Y1639147D01*
G01X427328Y1628947D02*
X431928D01*
G01X427328Y1639147D02*
Y1628947D01*
G01X420350Y1631932D02*
Y1638332D01*
G01X431251Y1616737D02*
X434451D01*
G01X431251Y1622937D02*
Y1616737D01*
G01X434451Y1622937D02*
X431251D01*
G01X434451Y1616737D02*
Y1622937D01*
G01X431225Y1628019D02*
Y1624819D01*
G01X437425Y1628019D02*
X431225D01*
G01Y1624819D02*
X437425D01*
G01X431928Y1639147D02*
X427328D01*
G01Y1634047D02*
X431928D01*
G01X421755Y1649293D02*
Y1644693D01*
G01X431955D02*
Y1649293D01*
G01X421755Y1644693D02*
X431955D01*
G01X421765Y1644306D02*
Y1639706D01*
G01X431965Y1644306D02*
X421765D01*
G01X431965Y1639706D02*
Y1644306D01*
G01X421765Y1639706D02*
X431965D01*
G01X420280Y1640104D02*
Y1646504D01*
G01X438114Y1641017D02*
X434914D01*
G01Y1634817D02*
X438114D01*
G01X434914Y1641017D02*
Y1634817D01*
G01X431955Y1649293D02*
X421755D01*
G01X450079Y269742D02*
X449811Y269794D01*
X449504Y269949D01*
X449312Y270207D01*
X449236Y270569D01*
X449312Y270930D01*
X449542Y271240D01*
X449887Y271395D01*
X450271D01*
X450501Y271499D01*
X450692Y271757D01*
X450769Y272119D01*
X450654Y272480D01*
X450386Y272739D01*
X450079Y272842D01*
X449772Y272739D01*
X449504Y272480D01*
X449389Y272119D01*
X449466Y271757D01*
X449657Y271499D01*
X449887Y271395D01*
X450271D01*
X450616Y271240D01*
X450846Y270930D01*
X450922Y270569D01*
X450846Y270207D01*
X450654Y269949D01*
X450347Y269794D01*
X450079Y269742D01*
G01X447400Y342962D02*
Y339762D01*
G01X453600Y342962D02*
X447400D01*
G01Y339762D02*
X453600D01*
G01X442100Y379262D02*
Y382462D01*
G01X435900Y379262D02*
X442100D01*
G01X435900Y382462D02*
Y379262D01*
G01X442100Y382462D02*
X435900D01*
G01X445712Y824536D02*
X457712D01*
G01X445712Y830536D02*
Y824536D01*
G01X457712Y830536D02*
X445712D01*
G01X445709Y831842D02*
X457709D01*
G01X445709Y837842D02*
Y831842D01*
G01X444232Y824536D02*
Y830536D01*
G01X444229Y831842D02*
Y837842D01*
G01X457709D02*
X445709D01*
G01X447026Y1154520D02*
Y1160520D01*
G01X447526Y1154520D02*
X459526D01*
G01X447526Y1160520D02*
Y1154520D01*
G01X459526Y1160520D02*
X447526D01*
G01X447026Y1162570D02*
Y1168570D01*
G01X447526Y1162570D02*
X459526D01*
G01X447526Y1168570D02*
Y1162570D01*
G01X459526Y1168570D02*
X447526D01*
G01X446228Y1263374D02*
X448468D01*
G01X447255Y1261749D02*
Y1264999D01*
G01X436274Y1272709D02*
Y1284709D01*
G01X438693Y1269542D02*
X456409D01*
G01X438693Y1305238D02*
Y1269542D01*
G01X441520Y1307559D02*
Y1309985D01*
G01X456409Y1305238D02*
X438693D01*
G01X447553Y1319920D02*
Y1307920D01*
G01X453553Y1319920D02*
X447553D01*
G01Y1307920D02*
X453553D01*
G01X449056Y1323163D02*
X455056D01*
G01X449056Y1335163D02*
Y1323163D01*
G01X438301Y1314629D02*
Y1320829D01*
G01X455056Y1335163D02*
X449056D01*
G01X442554Y1419059D02*
Y1422259D01*
G01X436354Y1419059D02*
X442554D01*
G01X436354Y1422259D02*
Y1419059D01*
G01X448694Y1415869D02*
X451894D01*
G01X448694Y1422069D02*
Y1415869D01*
G01X451894D02*
Y1422069D01*
G01X448449Y1413278D02*
Y1410078D01*
G01X454649Y1413278D02*
X448449D01*
G01Y1410078D02*
X454649D01*
G01X447174Y1405629D02*
X453374D01*
G01X447174Y1408829D02*
Y1405629D01*
G01X453374Y1408829D02*
X447174D01*
G01X442039Y1409904D02*
Y1413104D01*
G01X435839Y1409904D02*
X442039D01*
G01X435839Y1413104D02*
Y1409904D01*
G01X442039Y1413104D02*
X435839D01*
G01X439584Y1413675D02*
Y1416875D01*
G01X439574Y1406189D02*
Y1409389D01*
G01X444870Y1426368D02*
X451070D01*
G01D02*
Y1429568D01*
G01D02*
X444870D01*
G01D02*
Y1426368D01*
G01X451070Y1425869D02*
X444870D01*
G01D02*
Y1422669D01*
G01D02*
X451070D01*
G01D02*
Y1425869D01*
G01X442554Y1422259D02*
X436354D01*
G01X451894Y1422069D02*
X448694D01*
G01X440555Y1606977D02*
Y1617177D01*
G01X435955Y1606977D02*
X440555D01*
G01X435955Y1617177D02*
Y1606977D01*
G01Y1612077D02*
X440555D01*
G01Y1617177D02*
X435955D01*
G01X438670Y1617672D02*
X441870D01*
G01X438670Y1623872D02*
Y1617672D01*
G01X441870Y1623872D02*
X438670D01*
G01X441870Y1617672D02*
Y1623872D01*
G01X446260Y1624752D02*
X452460D01*
G01X446260Y1627952D02*
Y1624752D01*
G01X452460Y1627952D02*
X446260D01*
G01X443000Y1617832D02*
X446200D01*
G01X443000Y1624032D02*
Y1617832D01*
G01X446200Y1624032D02*
X443000D01*
G01X446200Y1617832D02*
Y1624032D01*
G01X437425Y1624819D02*
Y1628019D01*
G01X443395Y1634201D02*
X453595D01*
G01X443395Y1638801D02*
Y1634201D01*
G01X453595Y1638801D02*
X443395D01*
G01X448495D02*
Y1634201D01*
G01X441880Y1641087D02*
X438680D01*
G01X441880Y1634887D02*
Y1641087D01*
G01X438680Y1634887D02*
X441880D01*
G01X438680Y1641087D02*
Y1634887D01*
G01X438114Y1634817D02*
Y1641017D01*
G01X459650Y-534979D02*
Y-526979D01*
X458450Y-528579D01*
G01Y-534979D02*
X460850D01*
G01X467450D02*
X467650Y-533246D01*
X467950Y-531779D01*
X468350Y-530446D01*
X468850Y-528979D01*
X469650Y-526979D01*
X465650D01*
G01X475650Y-535246D02*
X475450Y-535112D01*
Y-534846D01*
X475650Y-534712D01*
X475850Y-534846D01*
Y-535112D01*
X475650Y-535246D01*
G01X481750Y-528312D02*
X482350Y-527512D01*
X483050Y-527112D01*
X483850Y-526979D01*
X484850Y-527246D01*
X485550Y-527912D01*
X485750Y-528712D01*
X485650Y-529513D01*
X485250Y-530179D01*
X483250Y-531512D01*
X482350Y-532446D01*
X481750Y-533779D01*
X481550Y-534979D01*
X485750D01*
G01X456900Y342962D02*
Y339762D01*
G01X463100Y342962D02*
X456900D01*
G01X463100Y339762D02*
Y342962D01*
G01X456900Y339762D02*
X463100D01*
G01X453600D02*
Y342962D01*
G01X462400Y378462D02*
Y384662D01*
X459200D01*
Y378462D01*
X462400D01*
G01X459189Y831842D02*
X471189D01*
G01X459189Y837842D02*
Y831842D01*
G01X471192Y830536D02*
X459192D01*
G01Y824536D02*
X471192D01*
G01X459192Y830536D02*
Y824536D01*
G01X457712D02*
Y830536D01*
G01X457709Y831842D02*
Y837842D01*
G01X471189D02*
X459189D01*
G01X455280Y941898D02*
Y929898D01*
G01X461280D02*
Y941898D01*
G01X455280Y929898D02*
X461280D01*
G01X461780Y930764D02*
X466380D01*
G01X461780Y940964D02*
Y930764D01*
G01X466380D02*
Y940964D01*
G01X466480Y930764D02*
X471080D01*
G01X466480Y940964D02*
Y930764D01*
G01X468107Y943385D02*
Y955385D01*
G01X462107Y943385D02*
X468107D01*
G01X462107Y955385D02*
Y943385D01*
G01X461280Y943380D02*
Y955380D01*
G01X455280Y943380D02*
X461280D01*
G01X455280Y955380D02*
Y943380D01*
G01X461280Y941898D02*
X455280D01*
G01X466380Y935864D02*
X461780D01*
G01X466380Y940964D02*
X461780D01*
G01X471080Y935864D02*
X466480D01*
G01X471080Y940964D02*
X466480D01*
G01X468280Y957860D02*
Y969860D01*
G01X462280Y957860D02*
X468280D01*
G01X462280Y969860D02*
Y957860D01*
G01X461280D02*
Y969860D01*
G01X455280Y957860D02*
X461280D01*
G01X455280Y969860D02*
Y957860D01*
G01X468107Y955385D02*
X462107D01*
G01X461280Y955380D02*
X455280D01*
G01X461280Y972340D02*
Y984340D01*
G01X455280Y972340D02*
X461280D01*
G01X455280Y984340D02*
Y972340D01*
G01X468280D02*
Y984340D01*
G01X462280Y972340D02*
X468280D01*
G01X462280Y984340D02*
Y972340D01*
G01X468280Y969860D02*
X462280D01*
G01X461280D02*
X455280D01*
G01X461280Y986820D02*
Y998820D01*
G01X455280Y986820D02*
X461280D01*
G01X455280Y998820D02*
Y986820D01*
G01X468280D02*
Y998820D01*
G01X462280Y986820D02*
X468280D01*
G01X462280Y998820D02*
Y986820D01*
G01X461280Y984340D02*
X455280D01*
G01X468280D02*
X462280D01*
G01X468280Y1001300D02*
Y1013300D01*
G01X462280Y1001300D02*
X468280D01*
G01X462280Y1013300D02*
Y1001300D01*
G01X468280Y1013300D02*
X462280D01*
G01X461280Y1001300D02*
Y1013300D01*
G01X455280Y1001300D02*
X461280D01*
G01X455280Y1013300D02*
Y1001300D01*
G01X461280Y1013300D02*
X455280D01*
G01X461280Y998820D02*
X455280D01*
G01X468280D02*
X462280D01*
G01X458951Y1029870D02*
X470951D01*
G01X458951Y1035870D02*
Y1029870D01*
G01X462280Y1027780D02*
Y1015780D01*
G01X468280Y1027780D02*
X462280D01*
G01X468280Y1015780D02*
Y1027780D01*
G01X462280Y1015780D02*
X468280D01*
G01X455280Y1027780D02*
Y1015780D01*
G01X461280Y1027780D02*
X455280D01*
G01X461280Y1015780D02*
Y1027780D01*
G01X455280Y1015780D02*
X461280D01*
G01X470951Y1035870D02*
X458951D01*
G01X459526Y1154520D02*
Y1160520D01*
G01X472026D02*
X460026D01*
G01Y1154520D02*
X472026D01*
G01X460026Y1160520D02*
Y1154520D01*
G01X459526Y1162570D02*
Y1168570D01*
G01X472026D02*
X460026D01*
G01Y1162570D02*
X472026D01*
G01X460026Y1168570D02*
Y1162570D01*
G01X465713Y1272709D02*
Y1284709D01*
G01X459713Y1272709D02*
X465713D01*
G01X459713Y1284709D02*
Y1272709D01*
G01X456409Y1269542D02*
Y1305238D01*
G01X465713Y1284709D02*
X459713D01*
G01X467231Y1276391D02*
X470431D01*
G01X467231Y1282591D02*
Y1276391D01*
G01X470431Y1282591D02*
X467231D01*
G01X455959Y1319920D02*
Y1307920D01*
G01X461959Y1319920D02*
X455959D01*
G01X461959Y1307920D02*
Y1319920D01*
G01X455959Y1307920D02*
X461959D01*
G01X453553D02*
Y1319920D01*
G01X455056Y1323163D02*
Y1335163D01*
G01X467190Y1314591D02*
X470390D01*
G01X467190Y1320791D02*
Y1314591D01*
G01X470390Y1320791D02*
X467190D01*
G01X462591Y1320492D02*
X465791D01*
G01X462591Y1326692D02*
Y1320492D01*
G01X465791D02*
Y1326692D01*
G01D02*
X462591D01*
G01X452280Y1399682D02*
X458480D01*
G01X452280Y1402882D02*
Y1399682D01*
G01X458480Y1402882D02*
X452280D01*
G01X458480Y1399682D02*
Y1402882D01*
G01X454649Y1410078D02*
Y1413278D01*
G01X453374Y1405629D02*
Y1408829D01*
G01X474367Y1430352D02*
Y1433452D01*
X473447D01*
X473140Y1433297D01*
X472910Y1432935D01*
X472833Y1432522D01*
X472910Y1432109D01*
X473102Y1431799D01*
X473447Y1431644D01*
X474367D01*
G01X471267Y1430972D02*
X471075Y1430662D01*
X470845Y1430455D01*
X470577Y1430352D01*
X470270Y1430455D01*
X470040Y1430662D01*
X469810Y1430972D01*
X469733Y1431385D01*
Y1433452D01*
G01X468128Y1431644D02*
X467860Y1432005D01*
X467630Y1432212D01*
X467323Y1432315D01*
X467055Y1432212D01*
X466863Y1432005D01*
X466710Y1431695D01*
X466672Y1431334D01*
X466710Y1431024D01*
X466863Y1430714D01*
X467093Y1430455D01*
X467362Y1430352D01*
X467668Y1430455D01*
X467937Y1430765D01*
X468090Y1431230D01*
X468128Y1431747D01*
X468052Y1432419D01*
X467937Y1432780D01*
X467745Y1433142D01*
X467477Y1433400D01*
X467208Y1433452D01*
X466940Y1433349D01*
X466748Y1433090D01*
G01X465028Y1431644D02*
X464760Y1432005D01*
X464530Y1432212D01*
X464223Y1432315D01*
X463955Y1432212D01*
X463763Y1432005D01*
X463610Y1431695D01*
X463572Y1431334D01*
X463610Y1431024D01*
X463763Y1430714D01*
X463993Y1430455D01*
X464262Y1430352D01*
X464568Y1430455D01*
X464837Y1430765D01*
X464990Y1431230D01*
X465028Y1431747D01*
X464952Y1432419D01*
X464837Y1432780D01*
X464645Y1433142D01*
X464377Y1433400D01*
X464108Y1433452D01*
X463840Y1433349D01*
X463648Y1433090D01*
G01X452460Y1624752D02*
Y1627952D01*
G01X453595Y1634201D02*
Y1638801D01*
G01X479650Y-508379D02*
X480150Y-509179D01*
X480750Y-509712D01*
X481450Y-509979D01*
X482250Y-509712D01*
X482850Y-509179D01*
X483450Y-508379D01*
X483650Y-507312D01*
Y-501979D01*
G01X475000Y241862D02*
X471900D01*
X472520Y242322D01*
G01X475000D02*
Y241402D01*
G01X472669Y831842D02*
X484669D01*
G01X472669Y837842D02*
Y831842D01*
G01X472672Y824536D02*
X484672D01*
G01X472672Y830536D02*
Y824536D01*
G01X484672Y830536D02*
X472672D01*
G01X471189Y831842D02*
Y837842D01*
G01X471192Y824536D02*
Y830536D01*
G01X484669Y837842D02*
X472669D01*
G01X475780Y930764D02*
Y940964D01*
G01X471180Y930764D02*
X475780D01*
G01X471180Y940964D02*
Y930764D01*
G01X471080D02*
Y940964D01*
G01X468917Y955305D02*
Y943305D01*
G01X474917D02*
Y955305D01*
G01X468917Y943305D02*
X474917D01*
G01X471180Y935864D02*
X475780D01*
G01Y940964D02*
X471180D01*
G01X475280Y957860D02*
Y969860D01*
G01X469280Y957860D02*
X475280D01*
G01X469280Y969860D02*
Y957860D01*
G01X474917Y955305D02*
X468917D01*
G01X475280Y969860D02*
X469280D01*
G01X475280Y972340D02*
Y984340D01*
G01X469280Y972340D02*
X475280D01*
G01X469280Y984340D02*
Y972340D01*
G01X475280Y986820D02*
Y998820D01*
G01X469280Y986820D02*
X475280D01*
G01X469280Y998820D02*
Y986820D01*
G01X475280Y984340D02*
X469280D01*
G01X475280Y1001300D02*
Y1013300D01*
G01X469280Y1001300D02*
X475280D01*
G01X469280Y1013300D02*
Y1001300D01*
G01X475280Y1013300D02*
X469280D01*
G01X475280Y998820D02*
X469280D01*
G01Y1027780D02*
Y1015780D01*
G01X475280Y1027780D02*
X469280D01*
G01X475280Y1015780D02*
Y1027780D01*
G01X469280Y1015780D02*
X475280D01*
G01X470951Y1029870D02*
Y1035870D01*
G01X474613Y1028524D02*
Y1034724D01*
X471413D01*
Y1028524D01*
X474613D01*
G01X472026Y1154520D02*
Y1160520D01*
G01X472526Y1154520D02*
X484526D01*
G01X472526Y1160520D02*
Y1154520D01*
G01X484526Y1160520D02*
X472526D01*
G01X484526Y1154520D02*
Y1160520D01*
G01X472026Y1162570D02*
Y1168570D01*
G01X472526Y1162570D02*
X484526D01*
G01X472526Y1168570D02*
Y1162570D01*
G01X484526Y1168570D02*
X472526D01*
G01X484526Y1162570D02*
Y1168570D01*
G01X478821Y1272709D02*
Y1284709D01*
G01X472821Y1272709D02*
X478821D01*
G01X472821Y1284709D02*
Y1272709D01*
G01X481221D02*
X487221D01*
G01X481221Y1284709D02*
Y1272709D01*
G01X478821Y1284709D02*
X472821D01*
G01X487221D02*
X481221D01*
G01X470431Y1276391D02*
Y1282591D01*
G01X479681Y1319920D02*
Y1307920D01*
G01X485681Y1319920D02*
X479681D01*
G01Y1307920D02*
X485681D01*
G01X486442Y1334923D02*
X480442D01*
Y1322923D01*
X486442D01*
Y1334923D01*
G01X470390Y1314591D02*
Y1320791D01*
G01X482557Y1396802D02*
Y1400002D01*
G01X476357Y1396802D02*
X482557D01*
G01X476357Y1400002D02*
Y1396802D01*
G01X482557Y1400002D02*
X476357D01*
G01X476323Y1403964D02*
Y1400764D01*
G01X482523Y1403964D02*
X476323D01*
G01X482523Y1400764D02*
Y1403964D01*
G01X476323Y1400764D02*
X482523D01*
G01X484036Y1392847D02*
Y1396047D01*
G01X477836Y1392847D02*
X484036D01*
G01X477836Y1396047D02*
Y1392847D01*
G01X484036Y1396047D02*
X477836D01*
G01X473800Y1409772D02*
Y1406572D01*
G01X480000Y1409772D02*
X473800D01*
G01X480000Y1406572D02*
Y1409772D01*
G01X473800Y1406572D02*
X480000D01*
G01X490787Y1430952D02*
Y1434052D01*
X489867D01*
X489560Y1433897D01*
X489330Y1433535D01*
X489253Y1433122D01*
X489330Y1432709D01*
X489522Y1432399D01*
X489867Y1432244D01*
X490787D01*
G01X487687Y1431572D02*
X487495Y1431262D01*
X487265Y1431055D01*
X486997Y1430952D01*
X486690Y1431055D01*
X486460Y1431262D01*
X486230Y1431572D01*
X486153Y1431985D01*
Y1434052D01*
G01X484548Y1432244D02*
X484280Y1432605D01*
X484050Y1432812D01*
X483743Y1432915D01*
X483475Y1432812D01*
X483283Y1432605D01*
X483130Y1432295D01*
X483092Y1431934D01*
X483130Y1431624D01*
X483283Y1431314D01*
X483513Y1431055D01*
X483782Y1430952D01*
X484088Y1431055D01*
X484357Y1431365D01*
X484510Y1431830D01*
X484548Y1432347D01*
X484472Y1433019D01*
X484357Y1433380D01*
X484165Y1433742D01*
X483897Y1434000D01*
X483628Y1434052D01*
X483360Y1433949D01*
X483168Y1433690D01*
G01X480797Y1430952D02*
X480720Y1431624D01*
X480605Y1432192D01*
X480452Y1432709D01*
X480260Y1433277D01*
X479953Y1434052D01*
X481487D01*
G01X483773Y1449792D02*
Y1437792D01*
G01X489773Y1449792D02*
X483773D01*
G01Y1437792D02*
X489773D01*
G01X568504Y1646023D02*
X478347D01*
G01D02*
Y1656672D01*
G01X544017Y1654792D02*
Y1662292D01*
X541777D01*
X541030Y1661917D01*
X540470Y1661042D01*
X540283Y1660042D01*
X540470Y1659042D01*
X540937Y1658292D01*
X541777Y1657917D01*
X544017D01*
G01X536517Y1654792D02*
Y1662292D01*
X534183D01*
X533437Y1661917D01*
X532970Y1661417D01*
X532783Y1660417D01*
X532970Y1659417D01*
X533530Y1658792D01*
X534183Y1658417D01*
X536517D01*
G01X534183D02*
X532783Y1654792D01*
G01X525283D02*
X529017D01*
Y1662292D01*
X525283D01*
G01X526777Y1658667D02*
X529017D01*
G01X521610Y1655792D02*
X520863Y1655167D01*
X520023Y1654792D01*
X519277D01*
X518530Y1655167D01*
X517970Y1655792D01*
X517690Y1656667D01*
X517877Y1657542D01*
X518343Y1658292D01*
X519183Y1658792D01*
X520303Y1659042D01*
X520957Y1659542D01*
X521237Y1660417D01*
X521050Y1661292D01*
X520583Y1661917D01*
X519930Y1662292D01*
X519277D01*
X518623Y1662042D01*
X518063Y1661417D01*
G01X514110Y1655792D02*
X513363Y1655167D01*
X512523Y1654792D01*
X511777D01*
X511030Y1655167D01*
X510470Y1655792D01*
X510190Y1656667D01*
X510377Y1657542D01*
X510843Y1658292D01*
X511683Y1658792D01*
X512803Y1659042D01*
X513457Y1659542D01*
X513737Y1660417D01*
X513550Y1661292D01*
X513083Y1661917D01*
X512430Y1662292D01*
X511777D01*
X511123Y1662042D01*
X510563Y1661417D01*
G01X505863Y1657292D02*
X503437D01*
G01X498923Y1654792D02*
Y1662292D01*
X495377D01*
G01X496683Y1658667D02*
X498923D01*
G01X490770Y1662292D02*
X488530D01*
G01X489650D02*
Y1654792D01*
G01X490770D02*
X488530D01*
G01X482150Y1662292D02*
Y1654792D01*
G01X484297Y1662292D02*
X480003D01*
G01X478347Y1665332D02*
Y1781456D01*
G01D02*
X568504D01*
G01X497990Y86642D02*
X501190D01*
G01X497990Y92842D02*
Y86642D01*
G01X497910Y79522D02*
X501110D01*
G01X497910Y85722D02*
Y79522D01*
G01X501110Y85722D02*
X497910D01*
G01X501190Y92842D02*
X497990D01*
G01X496937Y97079D02*
X509683D01*
G01X496937Y98232D02*
Y97079D01*
G01Y105122D02*
Y101972D01*
G01X509683Y109825D02*
X496937D01*
G01D02*
Y108092D01*
G01X500330Y127222D02*
X497130D01*
G01X500330Y121022D02*
Y127222D01*
G01X497130Y121022D02*
X500330D01*
G01X497130Y127222D02*
Y121022D01*
G01X500230Y147832D02*
X497030D01*
G01X500230Y141632D02*
Y147832D01*
G01X497030Y141632D02*
X500230D01*
G01X497030Y147832D02*
Y141632D01*
G01X494680Y242655D02*
X495042Y242425D01*
X495248Y242119D01*
X495300Y241774D01*
X495248Y241467D01*
X494990Y241160D01*
X494680Y240969D01*
X494370Y240930D01*
X494008Y241007D01*
X493750Y241275D01*
X493647Y241544D01*
Y241889D01*
G01Y241544D02*
X493492Y241314D01*
X493233Y241122D01*
X492923Y241045D01*
X492613Y241122D01*
X492355Y241314D01*
X492200Y241659D01*
X492252Y242004D01*
X492458Y242349D01*
G01X500063Y602567D02*
X496963D01*
X497583Y603027D01*
G01X500063D02*
Y602107D01*
G01X484669Y831842D02*
Y837842D01*
G01X484672Y824536D02*
Y830536D01*
G01X487221Y1272709D02*
Y1284709D01*
G01X499228Y1286512D02*
Y1298512D01*
G01X493228Y1286512D02*
X499228D01*
G01X493228Y1298512D02*
Y1286512D01*
G01X489363Y1276344D02*
X492563D01*
G01X489363Y1282544D02*
Y1276344D01*
G01X492563Y1282544D02*
X489363D01*
G01X492563Y1276344D02*
Y1282544D01*
G01X499228Y1298512D02*
X493228D01*
G01X488087Y1319920D02*
Y1307920D01*
G01X494087Y1319920D02*
X488087D01*
G01X494087Y1307920D02*
Y1319920D01*
G01X488087Y1307920D02*
X494087D01*
G01X485681D02*
Y1319920D01*
G01X503810Y1318239D02*
Y1320665D01*
G01X494719Y1333918D02*
X497919D01*
G01X494719Y1340118D02*
Y1333918D01*
G01X497919D02*
Y1340118D01*
G01X499413Y1327998D02*
X502613D01*
G01X499413Y1334198D02*
Y1327998D01*
G01X502613Y1334198D02*
X499413D01*
G01X497919Y1340118D02*
X494719D01*
G01X486970Y1411721D02*
X490170D01*
G01X486970Y1417921D02*
Y1411721D01*
G01X490170Y1417921D02*
X486970D01*
G01X490170Y1411721D02*
Y1417921D01*
G01X500573Y1449792D02*
Y1437792D01*
G01X506573Y1449792D02*
X500573D01*
G01Y1437792D02*
X506573D01*
G01X492173Y1449792D02*
Y1437792D01*
G01X498173Y1449792D02*
X492173D01*
G01X498173Y1437792D02*
Y1449792D01*
G01X492173Y1437792D02*
X498173D01*
G01X489773D02*
Y1449792D01*
G01X495202Y1665952D02*
Y1669052D01*
X495662Y1668432D01*
G01Y1665952D02*
X494742D01*
G01X490766Y1682583D02*
Y1679483D01*
X489232D01*
G01X490996Y1674759D02*
Y1677859D01*
X489999Y1675276D01*
X489002Y1677859D01*
Y1674759D01*
G01X490881Y1670035D02*
Y1673135D01*
X489117Y1670035D01*
Y1673135D01*
G01X490459Y1696757D02*
X489539D01*
G01X489999D02*
Y1693657D01*
G01X490459D02*
X489539D01*
G01X490766Y1689552D02*
X490574Y1689242D01*
X490344Y1689035D01*
X490076Y1688932D01*
X489769Y1689035D01*
X489539Y1689242D01*
X489309Y1689552D01*
X489232Y1689965D01*
Y1692032D01*
G01X490842Y1684208D02*
Y1687308D01*
G01X489386D02*
X490842Y1685396D01*
G01X489156Y1684208D02*
X490191Y1686275D01*
G01X490798Y1697952D02*
Y1701052D01*
G01X489188D02*
Y1697952D01*
G01Y1699502D02*
X490798D01*
G01X489232Y1712554D02*
X490766D01*
Y1715654D01*
X489232D01*
G01X489846Y1714156D02*
X490766D01*
G01X490727Y1707830D02*
Y1710930D01*
X489271D01*
G01X489807Y1709432D02*
X490727D01*
G01X489663Y1704302D02*
X488896D01*
Y1703372D01*
X489126Y1703062D01*
X489395Y1702855D01*
X489778Y1702752D01*
X490161Y1702855D01*
X490430Y1703062D01*
X490660Y1703372D01*
X490813Y1703734D01*
X490890Y1704147D01*
Y1704509D01*
X490813Y1704819D01*
X490660Y1705180D01*
X490430Y1705490D01*
X490200Y1705697D01*
X489893Y1705852D01*
X489625D01*
X489318Y1705749D01*
X489088Y1705542D01*
G01X489692Y1728381D02*
X489539Y1728536D01*
X489424Y1728795D01*
X489347Y1729156D01*
X489424Y1729466D01*
X489577Y1729673D01*
X489846Y1729828D01*
X490881D01*
Y1726728D01*
X489616D01*
X489347Y1726935D01*
X489194Y1727245D01*
X489117Y1727606D01*
X489194Y1727968D01*
X489424Y1728278D01*
X489692Y1728381D01*
X490881D01*
G01X489156Y1724845D02*
X489386Y1725000D01*
X489654Y1725103D01*
X489961D01*
X490306Y1724948D01*
X490574Y1724690D01*
X490766Y1724380D01*
X490919Y1723863D01*
X490957Y1723398D01*
X490881Y1722933D01*
X490766Y1722623D01*
X490536Y1722313D01*
X490267Y1722106D01*
X489999Y1722003D01*
X489731D01*
X489462Y1722106D01*
X489232Y1722261D01*
X489041Y1722468D01*
G01X490842Y1717279D02*
Y1720379D01*
X490076D01*
X489769Y1720224D01*
X489539Y1720017D01*
X489347Y1719707D01*
X489194Y1719346D01*
X489156Y1718829D01*
X489194Y1718312D01*
X489347Y1717951D01*
X489539Y1717641D01*
X489769Y1717434D01*
X490076Y1717279D01*
X490842D01*
G01X490751Y1731952D02*
X489793Y1735052D01*
X488835Y1731952D01*
G01X489180Y1733037D02*
X490406D01*
G01X501550Y69872D02*
X504750D01*
G01X501550Y76072D02*
Y69872D01*
G01X504750D02*
Y76072D01*
G01X505710Y69892D02*
X508910D01*
G01X505710Y76092D02*
Y69892D01*
G01X508910D02*
Y76092D01*
G01X501190Y86642D02*
Y92842D01*
G01X501110Y79522D02*
Y85722D01*
G01X504700Y85792D02*
X501500D01*
G01X504700Y79592D02*
Y85792D01*
G01X501500Y79592D02*
X504700D01*
G01X501500Y85792D02*
Y79592D01*
G01X504750Y76072D02*
X501550D01*
G01X508910Y85762D02*
X505710D01*
G01X508910Y79562D02*
Y85762D01*
G01X505710Y79562D02*
X508910D01*
G01X505710Y85762D02*
Y79562D01*
G01X508910Y76092D02*
X505710D01*
G01X509683Y97079D02*
Y97462D01*
G01Y101792D02*
Y104612D01*
G01Y108452D02*
Y109825D01*
G01X520265Y109150D02*
X517115D01*
G01Y105950D02*
X520265D01*
G01Y112660D02*
X517115D01*
G01Y109460D02*
X520265D01*
G01X504870Y127232D02*
X501670D01*
G01X504870Y121032D02*
Y127232D01*
G01X501670Y121032D02*
X504870D01*
G01X501670Y127232D02*
Y121032D01*
G01X508920Y127282D02*
X505720D01*
G01X508920Y121082D02*
Y127282D01*
G01X505720Y121082D02*
X508920D01*
G01X505720Y127282D02*
Y121082D01*
G01X504890Y147822D02*
X501690D01*
G01X504890Y141622D02*
Y147822D01*
G01X501690Y141622D02*
X504890D01*
G01X501690Y147822D02*
Y141622D01*
G01X508960Y147792D02*
X505760D01*
G01X508960Y141592D02*
Y147792D01*
G01X505760Y141592D02*
X508960D01*
G01X505760Y147792D02*
Y141592D01*
G01X535226Y1171318D02*
G03I-9950J0D01*
G01X508699Y1274888D02*
X510939D01*
G01X509726Y1273263D02*
Y1276513D01*
G01X501164Y1281056D02*
X518880D01*
G01X501164Y1316752D02*
Y1281056D01*
G01X511809Y1333346D02*
Y1321346D01*
G01D02*
X517809D01*
G01X518880Y1316752D02*
X501164D01*
G01X512199Y1337378D02*
X518199D01*
G01X512199Y1349378D02*
Y1337378D01*
G01X517809Y1333346D02*
X511809D01*
G01X502613Y1327998D02*
Y1334198D01*
G01X518199Y1349378D02*
X512199D01*
G01X506573Y1437792D02*
Y1449792D01*
G01X503804Y1668535D02*
X503574Y1668845D01*
X503306Y1669000D01*
X502999Y1669052D01*
X502616Y1668949D01*
X502348Y1668690D01*
X502271Y1668380D01*
X502309Y1668070D01*
X502463Y1667812D01*
X503229Y1667295D01*
X503574Y1666934D01*
X503804Y1666417D01*
X503881Y1665952D01*
X502271D01*
G01X511793Y1666572D02*
X511563Y1666210D01*
X511257Y1666004D01*
X510912Y1665952D01*
X510605Y1666004D01*
X510298Y1666262D01*
X510107Y1666572D01*
X510068Y1666882D01*
X510145Y1667244D01*
X510413Y1667502D01*
X510682Y1667605D01*
X511027D01*
G01X510682D02*
X510452Y1667760D01*
X510260Y1668019D01*
X510183Y1668329D01*
X510260Y1668639D01*
X510452Y1668897D01*
X510797Y1669052D01*
X511142Y1669000D01*
X511487Y1668794D01*
G01X533120Y33762D02*
X536320D01*
G01X533120Y39962D02*
Y33762D01*
G01X528120D02*
X531320D01*
G01X528120Y39962D02*
Y33762D01*
G01X531320D02*
Y39962D01*
G01X536320D02*
X533120D01*
G01X531320D02*
X528120D01*
G01X524300Y108900D02*
Y102700D01*
X527500D01*
Y108900D01*
X524300D01*
G01X527500Y109600D02*
Y115800D01*
X524300D01*
Y109600D01*
X527500D01*
G01X520269Y269752D02*
Y272852D01*
X520729Y272232D01*
G01Y269752D02*
X519809D01*
G01X519743Y603360D02*
X520105Y603130D01*
X520311Y602824D01*
X520363Y602479D01*
X520311Y602172D01*
X520053Y601865D01*
X519743Y601674D01*
X519433Y601635D01*
X519071Y601712D01*
X518813Y601980D01*
X518710Y602249D01*
Y602594D01*
G01Y602249D02*
X518555Y602019D01*
X518296Y601827D01*
X517986Y601750D01*
X517676Y601827D01*
X517418Y602019D01*
X517263Y602364D01*
X517315Y602709D01*
X517521Y603054D01*
G01X541190Y811121D02*
G03I-9950J0D01*
G01X526897Y1286512D02*
Y1298512D01*
G01X520897Y1286512D02*
X526897D01*
G01X520897Y1298512D02*
Y1286512D01*
G01X518880Y1281056D02*
Y1316752D01*
G01X526897Y1298512D02*
X520897D01*
G01X520215Y1333346D02*
Y1321346D01*
G01X526215D02*
Y1333346D01*
G01X520215Y1321346D02*
X526215D01*
G01X517809D02*
Y1333346D01*
G01X528452Y1311006D02*
X531652D01*
G01X528452Y1317206D02*
Y1311006D01*
G01X531652Y1317206D02*
X528452D01*
G01X531652Y1311006D02*
Y1317206D01*
G01X526215Y1333346D02*
X520215D01*
G01X518199Y1337378D02*
Y1349378D01*
G01X531823Y1350947D02*
X535023D01*
G01X531823Y1357147D02*
Y1350947D01*
G01X527329Y1356991D02*
X530529D01*
G01X527329Y1363191D02*
Y1356991D01*
G01X530529Y1363191D02*
X527329D01*
G01X530529Y1356991D02*
Y1363191D01*
G01X535023Y1357147D02*
X531823D01*
G01X518364Y1665952D02*
Y1669052D01*
X519782Y1666830D01*
X517866D01*
G01X527541Y1666417D02*
X527311Y1666159D01*
X527043Y1666004D01*
X526698Y1665952D01*
X526353Y1666055D01*
X526085Y1666262D01*
X525893Y1666624D01*
X525855Y1667037D01*
X525931Y1667450D01*
X526123Y1667709D01*
X526391Y1667915D01*
X526660Y1667967D01*
X526928Y1667915D01*
X527273Y1667709D01*
X527158Y1669052D01*
X526123D01*
G01X538120Y33762D02*
X541320D01*
G01X538120Y39962D02*
Y33762D01*
G01X541320D02*
Y39962D01*
G01X536320Y33762D02*
Y39962D01*
G01X547009D02*
Y33762D01*
X550209D01*
Y39962D01*
X547009D01*
G01X541320D02*
X538120D01*
G01X547050Y87227D02*
Y93427D01*
G01X544980Y87227D02*
X547050D01*
G01X539770Y93427D02*
Y87227D01*
G01D02*
X541400D01*
G01X547050Y93427D02*
X545620D01*
G01X543850Y92072D02*
Y88702D01*
G01X541480Y93427D02*
X539770D01*
G01X542970Y88702D02*
Y92072D01*
G01X548950Y107027D02*
Y116827D01*
G01X551610Y107027D02*
X548950D01*
G01Y116827D02*
X552150D01*
G01X540930Y115632D02*
X544130D01*
G01X540930Y121832D02*
Y115632D01*
G01X544130D02*
Y121832D01*
G01X544770Y115632D02*
X547970D01*
G01X544770Y121832D02*
Y115632D01*
G01X547970D02*
Y121832D01*
G01X540925Y110992D02*
Y114192D01*
G01X534725Y110992D02*
X540925D01*
G01X534725Y114192D02*
Y110992D01*
G01X540925Y114192D02*
X534725D01*
G01X544130Y121832D02*
X540930D01*
G01X547970D02*
X544770D01*
G01X540077Y1307470D02*
Y1319470D01*
G01X534077Y1307470D02*
X540077D01*
G01X534077Y1319470D02*
Y1307470D01*
G01X546907Y1307450D02*
Y1319450D01*
G01X540907Y1307450D02*
X546907D01*
G01X540907Y1319450D02*
Y1307450D01*
G01X540077Y1319470D02*
X534077D01*
G01X546907Y1319450D02*
X540907D01*
G01X543937Y1356144D02*
Y1344144D01*
G01X549937Y1356144D02*
X543937D01*
G01Y1344144D02*
X549937D01*
G01X535023Y1350947D02*
Y1357147D01*
G01X544327Y1360176D02*
X550327D01*
G01X544327Y1372176D02*
Y1360176D01*
G01X550327Y1372176D02*
X544327D01*
G01X550736Y1436707D02*
X547636D01*
X548256Y1437167D01*
G01X550736D02*
Y1436247D01*
G01X635433Y1646023D02*
X545276D01*
G01D02*
Y1781456D01*
G01X535300Y1667244D02*
X535032Y1667605D01*
X534802Y1667812D01*
X534495Y1667915D01*
X534227Y1667812D01*
X534035Y1667605D01*
X533882Y1667295D01*
X533844Y1666934D01*
X533882Y1666624D01*
X534035Y1666314D01*
X534265Y1666055D01*
X534534Y1665952D01*
X534840Y1666055D01*
X535109Y1666365D01*
X535262Y1666830D01*
X535300Y1667347D01*
X535224Y1668019D01*
X535109Y1668380D01*
X534917Y1668742D01*
X534649Y1669000D01*
X534380Y1669052D01*
X534112Y1668949D01*
X533920Y1668690D01*
G01X542523Y1665952D02*
X542446Y1666624D01*
X542331Y1667192D01*
X542178Y1667709D01*
X541986Y1668277D01*
X541679Y1669052D01*
X543213D01*
G01X550320Y1665952D02*
X550052Y1666004D01*
X549745Y1666159D01*
X549553Y1666417D01*
X549477Y1666779D01*
X549553Y1667140D01*
X549783Y1667450D01*
X550128Y1667605D01*
X550512D01*
X550742Y1667709D01*
X550933Y1667967D01*
X551010Y1668329D01*
X550895Y1668690D01*
X550627Y1668949D01*
X550320Y1669052D01*
X550013Y1668949D01*
X549745Y1668690D01*
X549630Y1668329D01*
X549707Y1667967D01*
X549898Y1667709D01*
X550128Y1667605D01*
X550512D01*
X550857Y1667450D01*
X551087Y1667140D01*
X551163Y1666779D01*
X551087Y1666417D01*
X550895Y1666159D01*
X550588Y1666004D01*
X550320Y1665952D01*
G01X545276Y1781456D02*
X635433D01*
G01X553120Y33762D02*
X556320D01*
G01X553120Y39962D02*
Y33762D01*
G01X556320D02*
Y39962D01*
G01X564700Y51082D02*
Y57282D01*
G01X561500Y51082D02*
X564700D01*
G01X561500Y57282D02*
Y51082D01*
G01X556320Y39962D02*
X553120D01*
G01X564700Y57282D02*
X561500D01*
G01X558750Y116827D02*
Y107027D01*
G01D02*
X556010D01*
G01X555990Y116827D02*
X558750D01*
G01X565865Y115732D02*
Y112532D01*
G01X572065Y115732D02*
X565865D01*
G01Y112532D02*
X572065D01*
G01X565805Y111222D02*
Y108022D01*
G01X572005Y111222D02*
X565805D01*
G01Y108022D02*
X572005D01*
G01X575378Y124519D02*
Y122297D01*
X575225Y121832D01*
X574918Y121522D01*
X574535Y121419D01*
X574152Y121522D01*
X573845Y121832D01*
X573692Y122297D01*
Y124519D01*
G01X572278Y122039D02*
X572048Y121677D01*
X571742Y121471D01*
X571397Y121419D01*
X571090Y121471D01*
X570783Y121729D01*
X570592Y122039D01*
X570553Y122349D01*
X570630Y122711D01*
X570898Y122969D01*
X571167Y123072D01*
X571512D01*
G01X571167D02*
X570937Y123227D01*
X570745Y123486D01*
X570668Y123796D01*
X570745Y124106D01*
X570937Y124364D01*
X571282Y124519D01*
X571627Y124467D01*
X571972Y124261D01*
G01X568335Y121419D02*
Y124519D01*
X568795Y123899D01*
G01Y121419D02*
X567875D01*
G01X565963Y124002D02*
X565733Y124312D01*
X565465Y124467D01*
X565158Y124519D01*
X564775Y124416D01*
X564507Y124157D01*
X564430Y123847D01*
X564468Y123537D01*
X564622Y123279D01*
X565388Y122762D01*
X565733Y122401D01*
X565963Y121884D01*
X566040Y121419D01*
X564430D01*
G01X584517Y991220D02*
G03I-9950J0D01*
G01X560117Y1318370D02*
X572117D01*
G01X560117Y1324370D02*
Y1318370D01*
G01X572117Y1333170D02*
X560117D01*
G01Y1327170D02*
X572117D01*
G01X560117Y1333170D02*
Y1327170D01*
G01X572117Y1324370D02*
X560117D01*
G01X552343Y1356144D02*
Y1344144D01*
G01X558343Y1356144D02*
X552343D01*
G01X558343Y1344144D02*
Y1356144D01*
G01X552343Y1344144D02*
X558343D01*
G01X549937D02*
Y1356144D01*
G01X550327Y1360176D02*
Y1372176D01*
G01X561681Y1665952D02*
Y1669052D01*
X562141Y1668432D01*
G01Y1665952D02*
X561221D01*
G01X558155Y1683043D02*
Y1679943D01*
X556621D01*
G01X558385Y1675219D02*
Y1678319D01*
X557388Y1675736D01*
X556391Y1678319D01*
Y1675219D01*
G01X558270Y1670495D02*
Y1673595D01*
X556506Y1670495D01*
Y1673595D01*
G01X558187Y1698412D02*
Y1701512D01*
G01X556577D02*
Y1698412D01*
G01Y1699962D02*
X558187D01*
G01X557848Y1697217D02*
X556928D01*
G01X557388D02*
Y1694117D01*
G01X557848D02*
X556928D01*
G01X558155Y1690012D02*
X557963Y1689702D01*
X557733Y1689495D01*
X557465Y1689392D01*
X557158Y1689495D01*
X556928Y1689702D01*
X556698Y1690012D01*
X556621Y1690425D01*
Y1692492D01*
G01X558231Y1684668D02*
Y1687768D01*
G01X556775D02*
X558231Y1685856D01*
G01X556545Y1684668D02*
X557580Y1686735D01*
G01X556621Y1713014D02*
X558155D01*
Y1716114D01*
X556621D01*
G01X557235Y1714616D02*
X558155D01*
G01X558116Y1708290D02*
Y1711390D01*
X556660D01*
G01X557196Y1709892D02*
X558116D01*
G01X557052Y1704762D02*
X556285D01*
Y1703832D01*
X556515Y1703522D01*
X556784Y1703315D01*
X557167Y1703212D01*
X557550Y1703315D01*
X557819Y1703522D01*
X558049Y1703832D01*
X558202Y1704194D01*
X558279Y1704607D01*
Y1704969D01*
X558202Y1705279D01*
X558049Y1705640D01*
X557819Y1705950D01*
X557589Y1706157D01*
X557282Y1706312D01*
X557014D01*
X556707Y1706209D01*
X556477Y1706002D01*
G01X557081Y1728841D02*
X556928Y1728996D01*
X556813Y1729255D01*
X556736Y1729616D01*
X556813Y1729926D01*
X556966Y1730133D01*
X557235Y1730288D01*
X558270D01*
Y1727188D01*
X557005D01*
X556736Y1727395D01*
X556583Y1727705D01*
X556506Y1728066D01*
X556583Y1728428D01*
X556813Y1728738D01*
X557081Y1728841D01*
X558270D01*
G01X556545Y1725305D02*
X556775Y1725460D01*
X557043Y1725563D01*
X557350D01*
X557695Y1725408D01*
X557963Y1725150D01*
X558155Y1724840D01*
X558308Y1724323D01*
X558346Y1723858D01*
X558270Y1723393D01*
X558155Y1723083D01*
X557925Y1722773D01*
X557656Y1722566D01*
X557388Y1722463D01*
X557120D01*
X556851Y1722566D01*
X556621Y1722721D01*
X556430Y1722928D01*
G01X558231Y1717739D02*
Y1720839D01*
X557465D01*
X557158Y1720684D01*
X556928Y1720477D01*
X556736Y1720167D01*
X556583Y1719806D01*
X556545Y1719289D01*
X556583Y1718772D01*
X556736Y1718411D01*
X556928Y1718101D01*
X557158Y1717894D01*
X557465Y1717739D01*
X558231D01*
G01X558140Y1732412D02*
X557182Y1735512D01*
X556224Y1732412D01*
G01X556569Y1733497D02*
X557795D01*
G01X570900Y33762D02*
X574100D01*
G01X570900Y39962D02*
Y33762D01*
G01X574100D02*
Y39962D01*
G01X566900Y33762D02*
X570100D01*
G01X566900Y39962D02*
Y33762D01*
G01X570100D02*
Y39962D01*
G01X579920Y51162D02*
X583120D01*
G01X579920Y57362D02*
Y51162D01*
G01X577800Y51122D02*
Y57322D01*
G01X574600Y51122D02*
X577800D01*
G01X574600Y57322D02*
Y51122D01*
G01X573180Y51082D02*
Y57282D01*
G01X569980Y51082D02*
X573180D01*
G01X569980Y57282D02*
Y51082D01*
G01X574100Y39962D02*
X570900D01*
G01X570100D02*
X566900D01*
G01X583120Y57362D02*
X579920D01*
G01X577800Y57322D02*
X574600D01*
G01X573180Y57282D02*
X569980D01*
G01X572065Y112532D02*
Y115732D01*
G01X572005Y108022D02*
Y111222D01*
G01X572117Y1318370D02*
Y1324370D01*
G01Y1327170D02*
Y1333170D01*
G01X570416Y1437500D02*
X570778Y1437270D01*
X570984Y1436964D01*
X571036Y1436619D01*
X570984Y1436312D01*
X570726Y1436005D01*
X570416Y1435814D01*
X570106Y1435775D01*
X569744Y1435852D01*
X569486Y1436120D01*
X569383Y1436389D01*
Y1436734D01*
G01Y1436389D02*
X569228Y1436159D01*
X568969Y1435967D01*
X568659Y1435890D01*
X568349Y1435967D01*
X568091Y1436159D01*
X567936Y1436504D01*
X567988Y1436849D01*
X568194Y1437194D01*
G01X568504Y1663570D02*
Y1646023D01*
G01X570283Y1668535D02*
X570053Y1668845D01*
X569785Y1669000D01*
X569478Y1669052D01*
X569095Y1668949D01*
X568827Y1668690D01*
X568750Y1668380D01*
X568788Y1668070D01*
X568942Y1667812D01*
X569708Y1667295D01*
X570053Y1666934D01*
X570283Y1666417D01*
X570360Y1665952D01*
X568750D01*
G01X578272Y1666572D02*
X578042Y1666210D01*
X577736Y1666004D01*
X577391Y1665952D01*
X577084Y1666004D01*
X576777Y1666262D01*
X576586Y1666572D01*
X576547Y1666882D01*
X576624Y1667244D01*
X576892Y1667502D01*
X577161Y1667605D01*
X577506D01*
G01X577161D02*
X576931Y1667760D01*
X576739Y1668019D01*
X576662Y1668329D01*
X576739Y1668639D01*
X576931Y1668897D01*
X577276Y1669052D01*
X577621Y1669000D01*
X577966Y1668794D01*
G01X633637Y1652682D02*
Y1660182D01*
X631397D01*
X630650Y1659807D01*
X630090Y1658932D01*
X629903Y1657932D01*
X630090Y1656932D01*
X630557Y1656182D01*
X631397Y1655807D01*
X633637D01*
G01X626137Y1652682D02*
Y1660182D01*
X623803D01*
X623057Y1659807D01*
X622590Y1659307D01*
X622403Y1658307D01*
X622590Y1657307D01*
X623150Y1656682D01*
X623803Y1656307D01*
X626137D01*
G01X623803D02*
X622403Y1652682D01*
G01X614903D02*
X618637D01*
Y1660182D01*
X614903D01*
G01X616397Y1656557D02*
X618637D01*
G01X611230Y1653682D02*
X610483Y1653057D01*
X609643Y1652682D01*
X608897D01*
X608150Y1653057D01*
X607590Y1653682D01*
X607310Y1654557D01*
X607497Y1655432D01*
X607963Y1656182D01*
X608803Y1656682D01*
X609923Y1656932D01*
X610577Y1657432D01*
X610857Y1658307D01*
X610670Y1659182D01*
X610203Y1659807D01*
X609550Y1660182D01*
X608897D01*
X608243Y1659932D01*
X607683Y1659307D01*
G01X603730Y1653682D02*
X602983Y1653057D01*
X602143Y1652682D01*
X601397D01*
X600650Y1653057D01*
X600090Y1653682D01*
X599810Y1654557D01*
X599997Y1655432D01*
X600463Y1656182D01*
X601303Y1656682D01*
X602423Y1656932D01*
X603077Y1657432D01*
X603357Y1658307D01*
X603170Y1659182D01*
X602703Y1659807D01*
X602050Y1660182D01*
X601397D01*
X600743Y1659932D01*
X600183Y1659307D01*
G01X595483Y1655182D02*
X593057D01*
G01X588543Y1652682D02*
Y1660182D01*
X584997D01*
G01X586303Y1656557D02*
X588543D01*
G01X580390Y1660182D02*
X578150D01*
G01X579270D02*
Y1652682D01*
G01X580390D02*
X578150D01*
G01X571770Y1660182D02*
Y1652682D01*
G01X573917Y1660182D02*
X569623D01*
G01X568504Y1781456D02*
Y1738490D01*
G01X583120Y51162D02*
Y57362D01*
G01X596805Y51082D02*
X600005D01*
G01X596805Y57282D02*
Y51082D01*
G01X595697D02*
Y57282D01*
G01X592497Y51082D02*
X595697D01*
G01X592497Y57282D02*
Y51082D01*
G01X600005Y57282D02*
X596805D01*
G01X595697D02*
X592497D01*
G01X591700Y55262D02*
Y61462D01*
X588500D01*
Y55262D01*
X591700D01*
G01X595620Y86762D02*
X598820D01*
G01X595620Y92962D02*
Y86762D01*
G01X590620D02*
X593820D01*
G01X590620Y92962D02*
Y86762D01*
G01X593820D02*
Y92962D01*
G01X598820D02*
X595620D01*
G01X593820D02*
X590620D01*
G01X598163Y746346D02*
X601363D01*
G01X598163Y752546D02*
Y746346D01*
G01X601363Y752546D02*
X598163D01*
G01X593997Y746330D02*
X597197D01*
G01X593997Y752530D02*
Y746330D01*
G01X597197Y752530D02*
X593997D01*
G01X597197Y746330D02*
Y752530D01*
G01X583906Y749487D02*
Y746287D01*
G01X590106Y749487D02*
X583906D01*
G01X590106Y746287D02*
Y749487D01*
G01X583906Y746287D02*
X590106D01*
G01X597822Y739355D02*
Y742555D01*
G01X591622Y739355D02*
X597822D01*
G01X591622Y742555D02*
Y739355D01*
G01X597822Y742555D02*
X591622D01*
G01X590812Y739385D02*
Y742585D01*
G01X584612Y739385D02*
X590812D01*
G01X584612Y742585D02*
Y739385D01*
G01X590812Y742585D02*
X584612D01*
G01X593676Y752565D02*
X590476D01*
G01X593676Y746365D02*
Y752565D01*
G01X590476Y746365D02*
X593676D01*
G01X590476Y752565D02*
Y746365D01*
G01X584843Y1665952D02*
Y1669052D01*
X586261Y1666830D01*
X584345D01*
G01X594020Y1666417D02*
X593790Y1666159D01*
X593522Y1666004D01*
X593177Y1665952D01*
X592832Y1666055D01*
X592564Y1666262D01*
X592372Y1666624D01*
X592334Y1667037D01*
X592410Y1667450D01*
X592602Y1667709D01*
X592870Y1667915D01*
X593139Y1667967D01*
X593407Y1667915D01*
X593752Y1667709D01*
X593637Y1669052D01*
X592602D01*
G01X609370Y51092D02*
X612570D01*
G01X609370Y57292D02*
Y51092D01*
G01X612570D02*
Y57292D01*
G01X607930Y51082D02*
Y57282D01*
G01X604730Y51082D02*
X607930D01*
G01X604730Y57282D02*
Y51082D01*
G01X603950D02*
Y57282D01*
G01X600750Y51082D02*
X603950D01*
G01X600750Y57282D02*
Y51082D01*
G01X600005D02*
Y57282D01*
G01X612570Y57292D02*
X609370D01*
G01X607930Y57282D02*
X604730D01*
G01X603950D02*
X600750D01*
G01X598820Y86762D02*
Y92962D01*
G01X607261Y147073D02*
Y143873D01*
G01X613461Y147073D02*
X607261D01*
G01X613461Y143873D02*
Y147073D01*
G01X607261Y143873D02*
X613461D01*
G01X607428Y153488D02*
Y150288D01*
G01X613628D02*
Y153488D01*
G01X607428Y150288D02*
X613628D01*
G01Y153488D02*
X607428D01*
G01X613357Y398549D02*
X619557D01*
G01X613357Y401749D02*
Y398549D01*
G01X619557Y401749D02*
X613357D01*
G01Y402579D02*
X619557D01*
G01X613357Y405779D02*
Y402579D01*
G01X619557Y405779D02*
X613357D01*
G01X613150Y748865D02*
X616350D01*
G01X613150Y755065D02*
Y748865D01*
G01X606650Y748365D02*
X609850D01*
G01X606650Y754565D02*
Y748365D01*
G01X609850D02*
Y754565D01*
G01X610160Y742370D02*
X613360D01*
G01X610160Y748570D02*
Y742370D01*
G01X613360Y748570D02*
X610160D01*
G01X613360Y742370D02*
Y748570D01*
G01X601363Y746346D02*
Y752546D01*
G01X604876Y752565D02*
X601676D01*
G01X604876Y746365D02*
Y752565D01*
G01X601676Y746365D02*
X604876D01*
G01X601676Y752565D02*
Y746365D01*
G01X613150Y755865D02*
X616350D01*
G01X613150Y762065D02*
Y755865D01*
G01X616350Y762065D02*
X613150D01*
G01Y762865D02*
X616350D01*
G01X613150Y769065D02*
Y762865D01*
G01X616350Y769065D02*
X613150D01*
G01X616350Y755065D02*
X613150D01*
G01X609850Y754565D02*
X606650D01*
G01X606625Y755930D02*
X609825D01*
G01X606625Y762130D02*
Y755930D01*
G01X609825Y762130D02*
X606625D01*
G01X609825Y755930D02*
Y762130D01*
G01X608538Y776312D02*
Y773112D01*
G01X614738Y776312D02*
X608538D01*
G01X614738Y773112D02*
Y776312D01*
G01X608538Y773112D02*
X614738D01*
G01X605740Y881997D02*
X608940D01*
G01X605740Y888197D02*
Y881997D01*
G01X608940D02*
Y888197D01*
G01X604030Y892964D02*
Y889764D01*
G01X610230Y892964D02*
X604030D01*
G01X610230Y889764D02*
Y892964D01*
G01X604030Y889764D02*
X610230D01*
G01X604030Y896984D02*
Y893784D01*
G01X610230Y896984D02*
X604030D01*
G01X610230Y893784D02*
Y896984D01*
G01X604030Y893784D02*
X610230D01*
G01X608940Y888197D02*
X605740D01*
G01X616458Y941476D02*
X610258D01*
G01D02*
Y938278D01*
G01D02*
X616458D01*
G01X601779Y1667244D02*
X601511Y1667605D01*
X601281Y1667812D01*
X600974Y1667915D01*
X600706Y1667812D01*
X600514Y1667605D01*
X600361Y1667295D01*
X600323Y1666934D01*
X600361Y1666624D01*
X600514Y1666314D01*
X600744Y1666055D01*
X601013Y1665952D01*
X601319Y1666055D01*
X601588Y1666365D01*
X601741Y1666830D01*
X601779Y1667347D01*
X601703Y1668019D01*
X601588Y1668380D01*
X601396Y1668742D01*
X601128Y1669000D01*
X600859Y1669052D01*
X600591Y1668949D01*
X600399Y1668690D01*
G01X609002Y1665952D02*
X608925Y1666624D01*
X608810Y1667192D01*
X608657Y1667709D01*
X608465Y1668277D01*
X608158Y1669052D01*
X609692D01*
G01X615150Y36252D02*
Y33052D01*
G01X621350Y36252D02*
X615150D01*
G01X621350Y33052D02*
Y36252D01*
G01X615150Y33052D02*
X621350D01*
G01X621320Y37102D02*
Y40302D01*
G01X615120Y37102D02*
X621320D01*
G01X615120Y40302D02*
Y37102D01*
G01X621320Y40302D02*
X615120D01*
G01X629530Y54182D02*
X632730D01*
G01X629530Y60382D02*
Y54182D01*
G01X621697Y51082D02*
Y57282D01*
G01X618497Y51082D02*
X621697D01*
G01X618497Y57282D02*
Y51082D01*
G01X629460Y47192D02*
X632660D01*
G01X629460Y53392D02*
Y47192D01*
G01X632660Y53392D02*
X629460D01*
G01X620690Y47392D02*
X617490D01*
G01X620690Y41192D02*
Y47392D01*
G01X617490Y41192D02*
X620690D01*
G01X617490Y47392D02*
Y41192D01*
G01X632730Y60382D02*
X629530D01*
G01X622190Y62872D02*
Y59672D01*
G01X628390Y62872D02*
X622190D01*
G01Y59672D02*
X628390D01*
G01D02*
Y62872D01*
G01X621697Y57282D02*
X618497D01*
G01X630183Y145342D02*
Y148542D01*
G01X623983Y145342D02*
X630183D01*
G01X623983Y148542D02*
Y145342D01*
G01X630183Y148542D02*
X623983D01*
G01X630181Y149959D02*
Y153159D01*
G01X623981Y149959D02*
X630181D01*
G01X623981Y153159D02*
Y149959D01*
G01X622414Y160076D02*
X619214D01*
G01X622414Y153876D02*
Y160076D01*
G01X619214Y153876D02*
X622414D01*
G01X619214Y160076D02*
Y153876D01*
G01X618608Y160050D02*
X615408D01*
G01X618608Y153850D02*
Y160050D01*
G01X615408Y153850D02*
X618608D01*
G01X615408Y160050D02*
Y153850D01*
G01X630181Y153159D02*
X623981D01*
G01X623231Y161532D02*
X626431D01*
G01X623231Y167732D02*
Y161532D01*
G01X626431Y167732D02*
X623231D01*
G01X626431Y161532D02*
Y167732D01*
G01X627402Y161487D02*
X630602D01*
G01X627402Y167687D02*
Y161487D01*
G01X630602Y167687D02*
X627402D01*
G01X630602Y161487D02*
Y167687D01*
G01X619557Y398549D02*
Y401749D01*
G01Y402579D02*
Y405779D01*
G01X630120Y422962D02*
Y419762D01*
G01X636320Y422962D02*
X630120D01*
G01Y419762D02*
X636320D01*
G01X630120Y429462D02*
X636320D01*
G01X630120Y432662D02*
Y429462D01*
G01X636320Y432662D02*
X630120D01*
G01X615120Y444462D02*
Y441262D01*
G01X621320Y444462D02*
X615120D01*
G01X621320Y441262D02*
Y444462D01*
G01X615120Y441262D02*
X621320D01*
G01X630120Y456262D02*
X636320D01*
G01X630120Y459462D02*
Y456262D01*
G01X636320Y459462D02*
X630120D01*
G01Y461262D02*
X636320D01*
G01X630120Y464462D02*
Y461262D01*
G01X615120Y464462D02*
Y461262D01*
G01X621320D02*
Y464462D01*
G01X615120Y461262D02*
X621320D01*
G01X615120Y459462D02*
Y456262D01*
G01X621320Y459462D02*
X615120D01*
G01X621320Y456262D02*
Y459462D01*
G01X615120Y456262D02*
X621320D01*
G01X615120Y454462D02*
Y451262D01*
G01X621320Y454462D02*
X615120D01*
G01X621320Y451262D02*
Y454462D01*
G01X615120Y451262D02*
X621320D01*
G01X615120Y449462D02*
Y446262D01*
G01X621320Y449462D02*
X615120D01*
G01X621320Y446262D02*
Y449462D01*
G01X615120Y446262D02*
X621320D01*
G01X630120Y476262D02*
X636320D01*
G01X630120Y479462D02*
Y476262D01*
G01Y471262D02*
X636320D01*
G01X630120Y474462D02*
Y471262D01*
G01X636320Y474462D02*
X630120D01*
G01Y466262D02*
X636320D01*
G01X630120Y469462D02*
Y466262D01*
G01X636320Y469462D02*
X630120D01*
G01X636320Y464462D02*
X630120D01*
G01X621320D02*
X615120D01*
G01X621320Y466262D02*
Y469462D01*
G01X615120Y466262D02*
X621320D01*
G01X615120Y469462D02*
Y466262D01*
G01X621320Y469462D02*
X615120D01*
G01X630120Y486262D02*
X636320D01*
G01X630120Y489462D02*
Y486262D01*
G01X636320Y489462D02*
X630120D01*
G01X636320Y479462D02*
X630120D01*
G01Y481262D02*
X636320D01*
G01X630120Y484462D02*
Y481262D01*
G01X636320Y484462D02*
X630120D01*
G01X616350Y748865D02*
Y755065D01*
G01Y755865D02*
Y762065D01*
G01Y762865D02*
Y769065D01*
G01X616458Y938278D02*
Y941476D01*
G01X622355Y992545D02*
Y980545D01*
G01X628355D02*
Y992545D01*
G01X622355Y980545D02*
X628355D01*
G01Y992545D02*
X622355D01*
G01X628340Y1009335D02*
Y1021335D01*
G01X622340Y1009335D02*
X628340D01*
G01X622340Y1021335D02*
Y1009335D01*
G01X630435Y1011321D02*
X636435D01*
G01X630435Y1023321D02*
Y1011321D01*
G01X628340Y1021335D02*
X622340D01*
G01X636435Y1023321D02*
X630435D01*
G01X627892Y1255736D02*
Y1258936D01*
G01X621692Y1255736D02*
X627892D01*
G01X621692Y1258936D02*
Y1255736D01*
G01X627892Y1251693D02*
Y1254893D01*
G01X621692Y1251693D02*
X627892D01*
G01X621692Y1254893D02*
Y1251693D01*
G01X627892Y1254893D02*
X621692D01*
G01X628299Y1259964D02*
Y1271964D01*
G01X622299Y1259964D02*
X628299D01*
G01X622299Y1271964D02*
Y1259964D01*
G01X628299Y1271964D02*
X622299D01*
G01X627892Y1258936D02*
X621692D01*
G01X616799Y1665952D02*
X616531Y1666004D01*
X616224Y1666159D01*
X616032Y1666417D01*
X615956Y1666779D01*
X616032Y1667140D01*
X616262Y1667450D01*
X616607Y1667605D01*
X616991D01*
X617221Y1667709D01*
X617412Y1667967D01*
X617489Y1668329D01*
X617374Y1668690D01*
X617106Y1668949D01*
X616799Y1669052D01*
X616492Y1668949D01*
X616224Y1668690D01*
X616109Y1668329D01*
X616186Y1667967D01*
X616377Y1667709D01*
X616607Y1667605D01*
X616991D01*
X617336Y1667450D01*
X617566Y1667140D01*
X617642Y1666779D01*
X617566Y1666417D01*
X617374Y1666159D01*
X617067Y1666004D01*
X616799Y1665952D01*
G01X646683Y38206D02*
X643483D01*
G01X646683Y32006D02*
Y38206D01*
G01X643483Y32006D02*
X646683D01*
G01X643483Y38206D02*
Y32006D01*
G01X636600Y49762D02*
Y55962D01*
G01X633400Y49762D02*
X636600D01*
G01X633400Y55962D02*
Y49762D01*
G01X640600D02*
Y55962D01*
G01X637400Y49762D02*
X640600D01*
G01X637400Y55962D02*
Y49762D01*
G01X632730Y54182D02*
Y60382D01*
G01X632660Y47192D02*
Y53392D01*
G01X636600Y55962D02*
X633400D01*
G01X640600D02*
X637400D01*
G01Y58762D02*
X640600D01*
G01X637400Y64962D02*
Y58762D01*
G01X640600Y64962D02*
X637400D01*
G01X640600Y58762D02*
Y64962D01*
G01X633400Y58762D02*
X636600D01*
G01X633400Y64962D02*
Y58762D01*
G01X636600Y64962D02*
X633400D01*
G01X636600Y58762D02*
Y64962D01*
G01X635203Y167796D02*
X632003D01*
G01X635203Y161596D02*
Y167796D01*
G01X632003Y161596D02*
X635203D01*
G01X632003Y167796D02*
Y161596D01*
G01X645120Y417962D02*
Y414762D01*
G01X651320Y417962D02*
X645120D01*
G01Y414762D02*
X651320D01*
G01X645120Y419762D02*
X651320D01*
G01X645120Y422962D02*
Y419762D01*
G01X651320Y422962D02*
X645120D01*
G01X636320Y419762D02*
Y422962D01*
G01X645120Y437262D02*
X651320D01*
G01X645120Y440462D02*
Y437262D01*
G01X651320Y440462D02*
X645120D01*
G01Y432962D02*
Y429762D01*
G01X651320Y432962D02*
X645120D01*
G01Y429762D02*
X651320D01*
G01X636320Y429462D02*
Y432662D01*
G01Y456262D02*
Y459462D01*
G01X645120Y464462D02*
Y461262D01*
G01D02*
X651320D01*
G01X645120Y459462D02*
Y456262D01*
G01X651320Y459462D02*
X645120D01*
G01Y456262D02*
X651320D01*
G01X645120Y454462D02*
Y451262D01*
G01X651320Y454462D02*
X645120D01*
G01Y451262D02*
X651320D01*
G01X645120Y449462D02*
Y446262D01*
G01X651320Y449462D02*
X645120D01*
G01Y446262D02*
X651320D01*
G01X636320Y461262D02*
Y464462D01*
G01X645120Y471262D02*
X651320D01*
G01X645120Y474462D02*
Y471262D01*
G01X651320Y474462D02*
X645120D01*
G01Y476262D02*
X651320D01*
G01X645120Y479462D02*
Y476262D01*
G01Y466262D02*
X651320D01*
G01X645120Y469462D02*
Y466262D01*
G01X651320Y469462D02*
X645120D01*
G01X651320Y464462D02*
X645120D01*
G01X636320Y476262D02*
Y479462D01*
G01Y471262D02*
Y474462D01*
G01Y466262D02*
Y469462D01*
G01X645120Y481262D02*
X651320D01*
G01X645120Y484462D02*
Y481262D01*
G01X651320Y484462D02*
X645120D01*
G01X651320Y479462D02*
X645120D01*
G01X636320Y486262D02*
Y489462D01*
G01Y481262D02*
Y484462D01*
G01X638560Y991434D02*
Y979434D01*
G01X644560D02*
Y991434D01*
G01X638560Y979434D02*
X644560D01*
G01Y991434D02*
X638560D01*
G01X644044Y1011321D02*
Y1023321D01*
G01X638044Y1011321D02*
X644044D01*
G01X638044Y1023321D02*
Y1011321D01*
G01X645527Y1003799D02*
X651527D01*
G01X645527Y1015799D02*
Y1003799D01*
G01X636435Y1011321D02*
Y1023321D01*
G01X644044D02*
X638044D01*
G01X651527Y1015799D02*
X645527D01*
G01X645935Y1257893D02*
X642735D01*
G01X645935Y1251693D02*
Y1257893D01*
G01X642735Y1251693D02*
X645935D01*
G01X642735Y1257893D02*
Y1251693D01*
G01X632073Y1251648D02*
X635273D01*
G01X632073Y1257848D02*
Y1251648D01*
G01X635273Y1257848D02*
X632073D01*
G01X635273Y1251648D02*
Y1257848D01*
G01X644299Y1259964D02*
Y1271964D01*
G01X638299Y1259964D02*
X644299D01*
G01X638299Y1271964D02*
Y1259964D01*
G01X644299Y1271964D02*
X638299D01*
G01X635433Y1660770D02*
Y1646023D01*
G01Y1708160D02*
Y1670840D01*
G01Y1781456D02*
Y1713580D01*
G01X647447Y32010D02*
X650647D01*
G01X647447Y38210D02*
Y32010D01*
G01X650647Y38210D02*
X647447D01*
G01X650647Y32010D02*
Y38210D01*
G01X659620Y402162D02*
Y397562D01*
G01X669820Y402162D02*
X659620D01*
G01Y397562D02*
X669820D01*
G01X661620Y406762D02*
X667820D01*
G01X661620Y409962D02*
Y406762D01*
G01X667820Y409962D02*
X661620D01*
G01Y402762D02*
X667820D01*
G01X661620Y405962D02*
Y402762D01*
G01X667820Y405962D02*
X661620D01*
G01X651320Y414762D02*
Y417962D01*
G01Y419762D02*
Y422962D01*
G01Y437262D02*
Y440462D01*
G01Y429762D02*
Y432962D01*
G01Y461262D02*
Y464462D01*
G01Y456262D02*
Y459462D01*
G01Y451262D02*
Y454462D01*
G01Y446262D02*
Y449462D01*
G01Y471262D02*
Y474462D01*
G01Y476262D02*
Y479462D01*
G01Y466262D02*
Y469462D01*
G01Y481262D02*
Y484462D01*
G01X662742Y773007D02*
X665942D01*
G01X662742Y779207D02*
Y773007D01*
G01X665942Y779207D02*
X662742D01*
G01X651629Y975028D02*
Y971828D01*
G01X657829Y975028D02*
X651629D01*
G01X657829Y971828D02*
Y975028D01*
G01X651629Y971828D02*
X657829D01*
G01X651963Y990841D02*
Y987641D01*
G01X658163Y990841D02*
X651963D01*
G01X658163Y987641D02*
Y990841D01*
G01X651963Y987641D02*
X658163D01*
G01X651963Y986921D02*
Y983721D01*
G01X658163Y986921D02*
X651963D01*
G01X658163Y983721D02*
Y986921D01*
G01X651963Y983721D02*
X658163D01*
G01X651527Y1003799D02*
Y1015799D01*
G01X651899Y1258564D02*
Y1255364D01*
G01X658099Y1258564D02*
X651899D01*
G01X658099Y1255364D02*
Y1258564D01*
G01X651899Y1255364D02*
X658099D01*
G01X660888Y1251295D02*
Y1254495D01*
G01X654688Y1251295D02*
X660888D01*
G01X654688Y1254495D02*
Y1251295D01*
G01X660888Y1254495D02*
X654688D01*
G01X655796Y1249527D02*
X652596D01*
G01X655796Y1243327D02*
Y1249527D01*
G01X652596Y1243327D02*
X655796D01*
G01X652596Y1249527D02*
Y1243327D01*
G01X657999Y1259964D02*
Y1271964D01*
G01X651999Y1259964D02*
X657999D01*
G01X651999Y1271964D02*
Y1259964D01*
G01X657999Y1271964D02*
X651999D01*
G01X666288Y1364039D02*
X660288D01*
Y1352039D01*
X666288D01*
Y1364039D01*
G01X663542Y1400135D02*
Y1406335D01*
G01X660342Y1400135D02*
X663542D01*
G01X660342Y1406335D02*
Y1400135D01*
G01X663542Y1406335D02*
X660342D01*
G01X675428Y33467D02*
X681628D01*
G01X675428Y36667D02*
Y33467D01*
G01X681628Y36667D02*
X675428D01*
G01X668480Y57282D02*
Y51082D01*
G01X671680Y53762D02*
Y55772D01*
G01X668480Y51082D02*
X670660D01*
G01X679650D02*
Y57282D01*
G01X676450Y51082D02*
X679650D01*
G01X676450Y57282D02*
Y51082D01*
G01X675680D02*
Y57282D01*
G01X673450Y51082D02*
X675680D01*
G01X672480Y55782D02*
Y53742D01*
G01X670890Y57282D02*
X668480D01*
G01X679650D02*
X676450D01*
G01X675680D02*
X673880D01*
G01X669770Y194972D02*
Y199572D01*
G01X664670D02*
Y194972D01*
G01X674870Y199572D02*
X664670D01*
G01X674870Y194972D02*
Y199572D01*
G01X664670Y194972D02*
X674870D01*
G01X664880Y203962D02*
Y200762D01*
G01X671080D02*
Y203962D01*
G01X664880Y200762D02*
X671080D01*
G01Y203962D02*
X664880D01*
G01Y207962D02*
Y204762D01*
G01X671080Y207962D02*
X664880D01*
G01X671080Y204762D02*
Y207962D01*
G01X664880Y204762D02*
X671080D01*
G01X664880Y211962D02*
Y208762D01*
G01X671080Y211962D02*
X664880D01*
G01X671080Y208762D02*
Y211962D01*
G01X664880Y208762D02*
X671080D01*
G01X669820Y397562D02*
Y402162D01*
G01X676195D02*
Y397562D01*
G01X686395Y402162D02*
X676195D01*
G01Y397562D02*
X686395D01*
G01X678195Y406762D02*
X684395D01*
G01X678195Y409962D02*
Y406762D01*
G01X684395Y409962D02*
X678195D01*
G01Y402762D02*
X684395D01*
G01X678195Y405962D02*
Y402762D01*
G01X684395Y405962D02*
X678195D01*
G01X667820Y406762D02*
Y409962D01*
G01Y402762D02*
Y405962D01*
G01X668754Y431037D02*
X674204D01*
G01X668754Y433337D02*
Y431037D01*
G01X674204Y433337D02*
X668754D01*
G01X674204Y431037D02*
Y433337D01*
G01X677353Y443635D02*
Y449085D01*
G01X675053Y443635D02*
X677353D01*
G01X675053Y449085D02*
Y443635D01*
G01X677353Y449085D02*
X675053D01*
G01X668754Y459383D02*
X674204D01*
G01X668754Y461683D02*
Y459383D01*
G01X674204D02*
Y461683D01*
G01D02*
X668754D01*
G01X670342Y768607D02*
X673542D01*
G01X670342Y774807D02*
Y768607D01*
G01X673542D02*
Y774807D01*
G01X668947Y762985D02*
X665747D01*
G01X668947Y756785D02*
Y762985D01*
G01X665747Y756785D02*
X668947D01*
G01X665747Y762985D02*
Y756785D01*
G01X674137Y763045D02*
X670937D01*
G01X674137Y756845D02*
Y763045D01*
G01X670937Y756845D02*
X674137D01*
G01X670937Y763045D02*
Y756845D01*
G01X665942Y773007D02*
Y779207D01*
G01X673542Y774807D02*
X670342D01*
G01X669285Y1257532D02*
Y1254332D01*
G01X675485Y1257532D02*
X669285D01*
G01X675485Y1254332D02*
Y1257532D01*
G01X669285Y1254332D02*
X675485D01*
G01X673999Y1259964D02*
Y1271964D01*
G01X667999Y1259964D02*
X673999D01*
G01X667999Y1271964D02*
Y1259964D01*
G01X673999Y1271964D02*
X667999D01*
G01X675784Y1340497D02*
X678024D01*
G01X676811Y1338872D02*
Y1342122D01*
G01X685965Y1346665D02*
Y1382361D01*
X668249D01*
Y1346665D01*
X685965D01*
G01X678677Y1398123D02*
Y1386123D01*
G01D02*
X684677D01*
G01X676807Y1385200D02*
Y1387626D01*
G01X684677Y1398123D02*
X678677D01*
G01X665808Y1392851D02*
X669008D01*
G01X665808Y1399051D02*
Y1392851D01*
G01X669008Y1399051D02*
X665808D01*
G01X669008Y1392851D02*
Y1399051D01*
G01X681628Y33467D02*
Y36667D01*
G01X682582Y36657D02*
Y33457D01*
G01X688782Y36657D02*
X682582D01*
G01X688782Y33457D02*
Y36657D01*
G01X682582Y33457D02*
X688782D01*
G01X696000Y51082D02*
Y57282D01*
G01X692800Y51082D02*
X696000D01*
G01X692800Y57282D02*
Y51082D01*
G01X683580D02*
Y57282D01*
G01X680380Y51082D02*
X683580D01*
G01X680380Y57282D02*
Y51082D01*
G01X684368D02*
X687568D01*
G01X684368Y57282D02*
Y51082D01*
G01X687568D02*
Y57282D01*
G01X688620Y51082D02*
X691820D01*
G01X688620Y57282D02*
Y51082D01*
G01X691820D02*
Y57282D01*
G01X696000D02*
X692800D01*
G01X683580D02*
X680380D01*
G01X687568D02*
X684368D01*
G01X691820D02*
X688620D01*
G01X684188Y85737D02*
Y91937D01*
G01X680988Y85737D02*
X684188D01*
G01X680988Y91937D02*
Y85737D01*
G01X684988D02*
X688188D01*
G01X684988Y91937D02*
Y85737D01*
G01X688188D02*
Y91937D01*
G01X694920Y100062D02*
X682920D01*
G01X694920Y94062D02*
Y100062D01*
G01X682920Y94062D02*
X694920D01*
G01X682920Y100062D02*
Y94062D01*
G01X684188Y91937D02*
X680988D01*
G01X688188D02*
X684988D01*
G01X680840Y120470D02*
Y114270D01*
X684040D01*
Y120470D01*
X680840D01*
G01X695160Y126632D02*
X698360D01*
G01X695160Y132832D02*
Y126632D01*
G01X698360Y132832D02*
X695160D01*
G01X686647Y380055D02*
X689847D01*
G01X686647Y386255D02*
Y380055D01*
G01X689847D02*
Y386255D01*
G01X690647Y380055D02*
X693847D01*
G01X690647Y386255D02*
Y380055D01*
G01X693847D02*
Y386255D01*
G01X689847D02*
X686647D01*
G01X693847D02*
X690647D01*
G01X686395Y397562D02*
Y402162D01*
G01X684395Y406762D02*
Y409962D01*
G01Y402762D02*
Y405962D01*
G01X686802Y412139D02*
Y417589D01*
G01X684502Y412139D02*
X686802D01*
G01X684502Y417589D02*
Y412139D01*
G01X691263Y408999D02*
X688063D01*
G01X691263Y402799D02*
Y408999D01*
G01X688063Y402799D02*
X691263D01*
G01X688063Y408999D02*
Y402799D01*
G01X686802Y417589D02*
X684502D01*
G01X693102Y439636D02*
X687652D01*
G01X693102Y437336D02*
Y439636D01*
G01X687652Y437336D02*
X693102D01*
G01X687652Y439636D02*
Y437336D01*
G01X693102Y442786D02*
X687652D01*
G01X693102Y440486D02*
Y442786D01*
G01X687652Y440486D02*
X693102D01*
G01X687652Y442786D02*
Y440486D01*
G01X693102Y443635D02*
Y445935D01*
G01X687652Y443635D02*
X693102D01*
G01X687652Y445935D02*
Y443635D01*
G01X693951Y440486D02*
X699401D01*
G01X693951Y442786D02*
Y440486D01*
G01X699401Y442786D02*
X693951D01*
G01Y439636D02*
Y434186D01*
G01X696251Y439636D02*
X693951D01*
G01Y434186D02*
X696251D01*
G01X693951Y443635D02*
X699401D01*
G01X693951Y445935D02*
Y443635D01*
G01X693102Y455384D02*
X687652D01*
G01X693102Y453084D02*
Y455384D01*
G01X687652Y453084D02*
X693102D01*
G01X687652Y455384D02*
Y453084D01*
G01X693102Y445935D02*
X687652D01*
G01X693102Y449085D02*
X687652D01*
G01X693102Y446785D02*
Y449085D01*
G01X687652Y446785D02*
X693102D01*
G01X687652Y449085D02*
Y446785D01*
G01X693951Y449934D02*
X699401D01*
G01X693951Y452234D02*
Y449934D01*
G01X699401Y452234D02*
X693951D01*
G01X693102D02*
X687652D01*
G01X693102Y449934D02*
Y452234D01*
G01X687652Y449934D02*
X693102D01*
G01X687652Y452234D02*
Y449934D01*
G01X699401Y445935D02*
X693951D01*
G01Y453084D02*
X696251D01*
G01X693951Y458534D02*
Y453084D01*
G01X696251Y458534D02*
X693951D01*
G01Y446785D02*
X699401D01*
G01X693951Y449085D02*
Y446785D01*
G01X699401Y449085D02*
X693951D01*
G01X684502Y480581D02*
Y475131D01*
G01X686802D02*
Y480581D01*
G01X684502Y475131D02*
X686802D01*
G01X688520Y492962D02*
X683920D01*
G01X688520Y482762D02*
Y492962D01*
G01X683920Y482762D02*
X688520D01*
G01X683920Y492962D02*
Y482762D01*
G01X693120Y484887D02*
X696320D01*
G01X693120Y491087D02*
Y484887D01*
G01X696320Y491087D02*
X693120D01*
G01X689120Y484887D02*
X692320D01*
G01X689120Y491087D02*
Y484887D01*
G01X692320Y491087D02*
X689120D01*
G01X692320Y484887D02*
Y491087D01*
G01X686802Y480581D02*
X684502D01*
G01X691710Y755561D02*
X694910D01*
G01X691710Y761761D02*
Y755561D01*
G01X694910Y761761D02*
X691710D01*
G01X694910Y755561D02*
Y761761D01*
G01X695736Y755561D02*
X698936D01*
G01X695736Y761761D02*
Y755561D01*
G01X698936Y761761D02*
X695736D01*
G01X687367Y785892D02*
X690567D01*
G01X687367Y792092D02*
Y785892D01*
G01X690567D02*
Y792092D01*
G01X693152Y778377D02*
Y781577D01*
G01X686952Y778377D02*
X693152D01*
G01X686952Y781577D02*
Y778377D01*
G01X693152Y781577D02*
X686952D01*
G01X690567Y792092D02*
X687367D01*
G01X681599Y1258564D02*
Y1255364D01*
G01X687799Y1258564D02*
X681599D01*
G01X687799Y1255364D02*
Y1258564D01*
G01X681599Y1255364D02*
X687799D01*
G01X695900Y1255462D02*
Y1258662D01*
G01X689700Y1255462D02*
X695900D01*
G01X689700Y1258662D02*
Y1255462D01*
G01X695900Y1258662D02*
X689700D01*
G01X686305Y1253060D02*
X683105D01*
G01X686305Y1246860D02*
Y1253060D01*
G01X683105Y1246860D02*
X686305D01*
G01X683105Y1253060D02*
Y1246860D01*
G01X687699Y1259964D02*
Y1271964D01*
G01X681699Y1259964D02*
X687699D01*
G01X681699Y1271964D02*
Y1259964D01*
G01X687699Y1271964D02*
X681699D01*
G01X693826Y1364039D02*
X687826D01*
Y1352039D01*
X693826D01*
Y1364039D01*
G01X698460Y1354380D02*
Y1360580D01*
X695260D01*
Y1354380D01*
X698460D01*
G01X687083Y1398623D02*
Y1386623D01*
G01X693083D02*
Y1398623D01*
G01X687083Y1386623D02*
X693083D01*
G01X684677Y1386123D02*
Y1398123D01*
G01X693083Y1398623D02*
X687083D01*
G01X688162Y1406840D02*
X700162D01*
G01X688162Y1412840D02*
Y1406840D01*
G01X700162Y1412840D02*
X688162D01*
G01X681743Y1602310D02*
X681973Y1602672D01*
X682279Y1602878D01*
X682624Y1602930D01*
X682931Y1602878D01*
X683238Y1602620D01*
X683429Y1602310D01*
X683468Y1602000D01*
X683391Y1601638D01*
X683123Y1601380D01*
X682854Y1601277D01*
X682509D01*
G01X682854D02*
X683084Y1601122D01*
X683276Y1600863D01*
X683353Y1600553D01*
X683276Y1600243D01*
X683084Y1599985D01*
X682739Y1599830D01*
X682394Y1599882D01*
X682049Y1600088D01*
G01X682886Y1623860D02*
Y1620760D01*
X682426Y1621380D01*
G01Y1623860D02*
X683346D01*
G01X721910Y-29800D02*
Y-13200D01*
X712310D01*
Y-29800D01*
X721910D01*
G01X699620Y-25617D02*
X699310Y-25425D01*
X699103Y-25195D01*
X699000Y-24927D01*
X699103Y-24620D01*
X699310Y-24390D01*
X699620Y-24160D01*
X700033Y-24083D01*
X702100D01*
G01X699000Y-21750D02*
X699052Y-21482D01*
X699207Y-21175D01*
X699465Y-20983D01*
X699827Y-20907D01*
X700188Y-20983D01*
X700498Y-21213D01*
X700653Y-21558D01*
Y-21942D01*
X700757Y-22172D01*
X701015Y-22363D01*
X701377Y-22440D01*
X701738Y-22325D01*
X701997Y-22057D01*
X702100Y-21750D01*
X701997Y-21443D01*
X701738Y-21175D01*
X701377Y-21060D01*
X701015Y-21137D01*
X700757Y-21328D01*
X700653Y-21558D01*
Y-21942D01*
X700498Y-22287D01*
X700188Y-22517D01*
X699827Y-22593D01*
X699465Y-22517D01*
X699207Y-22325D01*
X699052Y-22018D01*
X699000Y-21750D01*
G01X702100Y-18650D02*
X701997Y-18957D01*
X701738Y-19187D01*
X701428Y-19340D01*
X701015Y-19455D01*
X700550Y-19493D01*
X700085Y-19455D01*
X699672Y-19340D01*
X699362Y-19187D01*
X699103Y-18957D01*
X699000Y-18650D01*
X699103Y-18343D01*
X699362Y-18113D01*
X699672Y-17960D01*
X700085Y-17845D01*
X700550Y-17807D01*
X701015Y-17845D01*
X701428Y-17960D01*
X701738Y-18113D01*
X701997Y-18343D01*
X702100Y-18650D01*
G01X700197Y51082D02*
Y57282D01*
G01X696997Y51082D02*
X700197D01*
G01X696997Y57282D02*
Y51082D01*
G01X705997Y57282D02*
Y51082D01*
G01D02*
X709197D01*
G01D02*
Y57282D01*
G01X710267Y57322D02*
Y51122D01*
G01D02*
X713467D01*
G01X701190Y57272D02*
Y51072D01*
G01D02*
X704390D01*
G01D02*
Y57272D01*
G01X710400Y70562D02*
X713600D01*
G01X710400Y76762D02*
Y70562D01*
G01X700197Y57282D02*
X696997D01*
G01X709197D02*
X705997D01*
G01X713467Y57322D02*
X710267D01*
G01X704390Y57272D02*
X701190D01*
G01X705900Y73762D02*
X709100D01*
G01X705900Y79962D02*
Y73762D01*
G01X709100Y79962D02*
X705900D01*
G01X709100Y73762D02*
Y79962D01*
G01X706510Y81012D02*
X709710D01*
G01X706510Y87212D02*
Y81012D01*
G01X709710Y87212D02*
X706510D01*
G01X709710Y81012D02*
Y87212D01*
G01X701900Y73762D02*
X705100D01*
G01X701900Y79962D02*
Y73762D01*
G01X705100Y79962D02*
X701900D01*
G01X705100Y73762D02*
Y79962D01*
G01X710500Y81012D02*
X713700D01*
G01X710500Y87212D02*
Y81012D01*
G01X713700Y87212D02*
X710500D01*
G01X713600Y76762D02*
X710400D01*
G01X702560Y132802D02*
X699360D01*
G01X702560Y126602D02*
Y132802D01*
G01X699360Y126602D02*
X702560D01*
G01X699360Y132802D02*
Y126602D01*
G01X698360Y126632D02*
Y132832D01*
G01X696120Y402162D02*
Y397562D01*
G01X706320Y402162D02*
X696120D01*
G01X706320Y397562D02*
Y402162D01*
G01X696120Y397562D02*
X706320D01*
G01X704320Y406762D02*
Y409962D01*
G01X698120Y406762D02*
X704320D01*
G01X698120Y409962D02*
Y406762D01*
G01X704320Y409962D02*
X698120D01*
G01X704320Y402762D02*
Y405962D01*
G01X698120Y402762D02*
X704320D01*
G01X698120Y405962D02*
Y402762D01*
G01X704320Y405962D02*
X698120D01*
G01X698163Y413855D02*
Y410655D01*
G01X704363D02*
Y413855D01*
G01X698163Y410655D02*
X704363D01*
G01X712033Y410759D02*
Y416959D01*
G01X708833Y410759D02*
X712033D01*
G01X708833Y416959D02*
Y410759D01*
G01X707150Y423050D02*
Y417600D01*
G01X709450Y423050D02*
X707150D01*
G01X709450Y417600D02*
Y423050D01*
G01X707150Y417600D02*
X709450D01*
G01X697925Y419100D02*
Y415900D01*
G01X704125Y419100D02*
X697925D01*
G01X704125Y415900D02*
Y419100D01*
G01X697925Y415900D02*
X704125D01*
G01X697885Y423140D02*
Y419940D01*
G01X704085Y423140D02*
X697885D01*
G01X704085Y419940D02*
Y423140D01*
G01X697885Y419940D02*
X704085D01*
G01X704363Y413855D02*
X698163D01*
G01X712033Y416959D02*
X708833D01*
G01X699401Y440486D02*
Y442786D01*
G01X700250Y439636D02*
Y434186D01*
G01X702550Y439636D02*
X700250D01*
G01X702550Y434186D02*
Y439636D01*
G01X700250Y434186D02*
X702550D01*
G01X703400Y439636D02*
Y434186D01*
G01X705700Y439636D02*
X703400D01*
G01X705700Y434186D02*
Y439636D01*
G01X703400Y434186D02*
X705700D01*
G01X696251D02*
Y439636D01*
G01X697101D02*
Y434186D01*
G01X699401Y439636D02*
X697101D01*
G01X699401Y434186D02*
Y439636D01*
G01X697101Y434186D02*
X699401D01*
G01X706549Y439636D02*
Y434186D01*
G01X708849Y439636D02*
X706549D01*
G01X708849Y434186D02*
Y439636D01*
G01X706549Y434186D02*
X708849D01*
G01X699401Y443635D02*
Y445935D01*
G01X702550Y440485D02*
Y445935D01*
G01X700250Y440485D02*
X702550D01*
G01X700250Y445935D02*
Y440485D01*
G01X705700D02*
Y445935D01*
G01X703400Y440485D02*
X705700D01*
G01X703400Y445935D02*
Y440485D01*
G01X711999Y443635D02*
Y445935D01*
G01X706549Y443635D02*
X711999D01*
G01X706549Y445935D02*
Y443635D01*
G01X711999Y442786D02*
X706549D01*
G01X711999Y440486D02*
Y442786D01*
G01X706549Y440486D02*
X711999D01*
G01X706549Y442786D02*
Y440486D01*
G01X709699Y439636D02*
Y434186D01*
G01X711999Y439636D02*
X709699D01*
G01X711999Y434186D02*
Y439636D01*
G01X709699Y434186D02*
X711999D01*
G01X699401Y449934D02*
Y452234D01*
G01X702550Y445935D02*
X700250D01*
G01X708849Y453084D02*
Y458534D01*
G01X706549Y453084D02*
X708849D01*
G01X706549Y458534D02*
Y453084D01*
G01X708849Y458534D02*
X706549D01*
G01X705700Y453084D02*
Y458534D01*
G01X703400Y453084D02*
X705700D01*
G01X703400Y458534D02*
Y453084D01*
G01X705700Y458534D02*
X703400D01*
G01X702550Y453084D02*
Y458534D01*
G01X700250Y453084D02*
X702550D01*
G01X700250Y458534D02*
Y453084D01*
G01X702550Y458534D02*
X700250D01*
G01X699401Y453084D02*
Y458534D01*
G01X697101Y453084D02*
X699401D01*
G01X697101Y458534D02*
Y453084D01*
G01X699401Y458534D02*
X697101D01*
G01X705700Y445935D02*
X703400D01*
G01Y452235D02*
Y446785D01*
G01X705700Y452235D02*
X703400D01*
G01X705700Y446785D02*
Y452235D01*
G01X703400Y446785D02*
X705700D01*
G01X700250Y452235D02*
Y446785D01*
G01X702550Y452235D02*
X700250D01*
G01X702550Y446785D02*
Y452235D01*
G01X700250Y446785D02*
X702550D01*
G01X696251Y453084D02*
Y458534D01*
G01X711999Y445935D02*
X706549D01*
G01X711999Y449085D02*
X706549D01*
G01X711999Y446785D02*
Y449085D01*
G01X706549Y446785D02*
X711999D01*
G01X706549Y449085D02*
Y446785D01*
G01X711999Y452234D02*
X706549D01*
G01X711999Y449934D02*
Y452234D01*
G01X706549Y449934D02*
X711999D01*
G01X706549Y452234D02*
Y449934D01*
G01X699401Y446785D02*
Y449085D01*
G01X711999Y453084D02*
Y458534D01*
G01X709699Y453084D02*
X711999D01*
G01X709699Y458534D02*
Y453084D01*
G01X711999Y458534D02*
X709699D01*
G01X700250Y465682D02*
X705700D01*
G01X700250Y467982D02*
Y465682D01*
G01X705700Y467982D02*
X700250D01*
G01X705700Y465682D02*
Y467982D01*
G01X712320Y491062D02*
Y495662D01*
G01X702120Y491062D02*
X712320D01*
G01X702120Y495662D02*
Y491062D01*
G01X696320Y484887D02*
Y491087D01*
G01X706620Y486462D02*
Y483262D01*
G01X712820Y486462D02*
X706620D01*
G01Y483262D02*
X712820D01*
G01X706620Y490462D02*
Y487262D01*
G01X712820Y490462D02*
X706620D01*
G01Y487262D02*
X712820D01*
G01X712320Y495662D02*
X702120D01*
G01X699762Y755561D02*
X702962D01*
G01X699762Y761761D02*
Y755561D01*
G01X702962Y761761D02*
X699762D01*
G01X702962Y755561D02*
Y761761D01*
G01X698936Y755561D02*
Y761761D01*
G01X703788Y755561D02*
X706988D01*
G01X703788Y761761D02*
Y755561D01*
G01X706988Y761761D02*
X703788D01*
G01X706988Y755561D02*
Y761761D01*
G01X709088Y755561D02*
X712288D01*
G01X709088Y761761D02*
Y755561D01*
G01X712288Y761761D02*
X709088D01*
G01X712288Y755561D02*
Y761761D01*
G01X711299Y1258564D02*
Y1255364D01*
G01X717499Y1258564D02*
X711299D01*
G01Y1255364D02*
X717499D01*
G01X703662Y1252894D02*
Y1259094D01*
G01X700462Y1252894D02*
X703662D01*
G01X700462Y1259094D02*
Y1252894D01*
G01X703699Y1259964D02*
Y1271964D01*
G01X697699Y1259964D02*
X703699D01*
G01X697699Y1271964D02*
Y1259964D01*
G01X703699Y1271964D02*
X697699D01*
G01X711399Y1259964D02*
X717399D01*
G01X711399Y1271964D02*
Y1259964D01*
G01X717399Y1271964D02*
X711399D01*
G01X703662Y1259094D02*
X700462D01*
G01X706320Y1299562D02*
Y1302762D01*
G01X700120Y1299562D02*
X706320D01*
G01X700120Y1302762D02*
Y1299562D01*
G01X706320Y1302762D02*
X700120D01*
G01X709120D02*
Y1299562D01*
G01X715320Y1302762D02*
X709120D01*
G01Y1299562D02*
X715320D01*
G01X706320Y1295562D02*
Y1298762D01*
G01X700120Y1295562D02*
X706320D01*
G01X700120Y1298762D02*
Y1295562D01*
G01X706320Y1298762D02*
X700120D01*
G01X709120D02*
Y1295562D01*
G01X715320Y1298762D02*
X709120D01*
G01Y1295562D02*
X715320D01*
G01X705239Y1364039D02*
X699239D01*
Y1352039D01*
X705239D01*
Y1364039D01*
G01X724862Y1346665D02*
Y1382361D01*
X707146D01*
Y1346665D01*
X724862D01*
G01X715704Y1385200D02*
Y1387626D01*
G01X700230Y1400095D02*
X703430D01*
G01X700230Y1406295D02*
Y1400095D01*
G01X703430D02*
Y1406295D01*
G01X702351Y1392826D02*
X705551D01*
G01X702351Y1399026D02*
Y1392826D01*
G01X705551Y1399026D02*
X702351D01*
G01X705551Y1392826D02*
Y1399026D01*
G01X700162Y1406840D02*
Y1412840D01*
G01X703430Y1406295D02*
X700230D01*
G01X709242Y1562133D02*
Y1565333D01*
G01X703042Y1562133D02*
X709242D01*
G01X703042Y1565333D02*
Y1562133D01*
G01X709242Y1565333D02*
X703042D01*
G01X709212Y1586083D02*
Y1589283D01*
G01D02*
X703012D01*
G01Y1586083D02*
X709212D01*
G01X703012Y1589283D02*
Y1586083D01*
G01X709612Y1594023D02*
Y1597223D01*
G01X703412D02*
Y1594023D01*
G01X709612Y1597223D02*
X703412D01*
G01Y1594023D02*
X709612D01*
G01X709212Y1590083D02*
Y1593283D01*
G01X703012Y1590083D02*
X709212D01*
G01X703012Y1593283D02*
Y1590083D01*
G01X709212Y1593283D02*
X703012D01*
G01X710812Y1600383D02*
Y1603583D01*
G01X704612Y1600383D02*
X710812D01*
G01X704612Y1603583D02*
Y1600383D01*
G01X710812Y1603583D02*
X704612D01*
G01X713898Y1610402D02*
X710698D01*
G01Y1604202D02*
X713898D01*
G01X710698Y1610402D02*
Y1604202D01*
G01X706575Y1610411D02*
Y1604211D01*
X709775D01*
Y1610411D01*
X706575D01*
G01X709819Y1640251D02*
Y1643451D01*
G01D02*
X703619D01*
G01D02*
Y1640251D01*
G01D02*
X709819D01*
G01Y1633251D02*
Y1639451D01*
G01D02*
X706619D01*
G01D02*
Y1633251D01*
G01D02*
X709819D01*
G01X702619Y1639451D02*
Y1633251D01*
G01D02*
X705819D01*
G01D02*
Y1639451D01*
G01D02*
X702619D01*
G01X703483Y1665593D02*
Y1659393D01*
G01D02*
X706683D01*
G01D02*
Y1665593D01*
G01X706996Y1665442D02*
Y1662242D01*
G01D02*
X713196D01*
G01X706683Y1665593D02*
X703483D01*
G01X713196Y1665442D02*
X706996D01*
G01X713209Y1669441D02*
X707009D01*
G01D02*
Y1666241D01*
G01D02*
X713209D01*
G01X723044Y50445D02*
X726244D01*
G01X723044Y56645D02*
Y50445D01*
G01X726244D02*
Y56645D01*
G01X727693Y50445D02*
X730893D01*
G01X727693Y56645D02*
Y50445D01*
G01X718349D02*
X721549D01*
G01X718349Y56645D02*
Y50445D01*
G01X721549D02*
Y56645D01*
G01X713467Y51122D02*
Y57322D01*
G01X721567Y70562D02*
Y76762D01*
G01X718367Y70562D02*
X721567D01*
G01X718367Y76762D02*
Y70562D01*
G01X725557D02*
Y76762D01*
G01X722357Y70562D02*
X725557D01*
G01X722357Y76762D02*
Y70562D01*
G01X713600D02*
Y76762D01*
G01X717590Y70562D02*
Y76762D01*
G01X714390Y70562D02*
X717590D01*
G01X714390Y76762D02*
Y70562D01*
G01X726244Y56645D02*
X723044D01*
G01X730893D02*
X727693D01*
G01X721549D02*
X718349D01*
G01X729600Y82962D02*
X726400D01*
G01Y76762D02*
X729600D01*
G01X726400Y82962D02*
Y76762D01*
G01X714400Y84162D02*
Y80962D01*
G01X720600Y84162D02*
X714400D01*
G01X720600Y80962D02*
Y84162D01*
G01X714400Y80962D02*
X720600D01*
G01X713700Y81012D02*
Y87212D01*
G01X721800Y80962D02*
X725000D01*
G01X721800Y87162D02*
Y80962D01*
G01X725000Y87162D02*
X721800D01*
G01X725000Y80962D02*
Y87162D01*
G01X721567Y76762D02*
X718367D01*
G01X725557D02*
X722357D01*
G01X717590D02*
X714390D01*
G01X714120Y402162D02*
Y397562D01*
G01X724320Y402162D02*
X714120D01*
G01X724320Y397562D02*
Y402162D01*
G01X714120Y397562D02*
X724320D01*
G01X722320Y406762D02*
Y409962D01*
G01X716120Y406762D02*
X722320D01*
G01X716120Y409962D02*
Y406762D01*
G01X722320Y409962D02*
X716120D01*
G01X722320Y402762D02*
Y405962D01*
G01X716120Y402762D02*
X722320D01*
G01X716120Y405962D02*
Y402762D01*
G01X722320Y405962D02*
X716120D01*
G01X724597Y412139D02*
Y417589D01*
G01X722297Y412139D02*
X724597D01*
G01X722297Y417589D02*
Y412139D01*
G01X712947Y413869D02*
Y410669D01*
G01X719147D02*
Y413869D01*
G01X712947Y410669D02*
X719147D01*
G01X727360Y409782D02*
X733560D01*
G01X727360Y412982D02*
Y409782D01*
G01X724597Y417589D02*
X722297D01*
G01X719147Y413869D02*
X712947D01*
G01X733560Y412982D02*
X727360D01*
G01X734047Y433337D02*
X728597D01*
G01Y431037D02*
X734047D01*
G01X728597Y433337D02*
Y431037D01*
G01X712848Y437336D02*
X718298D01*
G01X712848Y439636D02*
Y437336D01*
G01X718298Y439636D02*
X712848D01*
G01X718298Y437336D02*
Y439636D01*
G01X725447Y449085D02*
Y443635D01*
G01X727747D02*
Y449085D01*
G01X725447Y443635D02*
X727747D01*
G01X712848D02*
X718298D01*
G01X712848Y445935D02*
Y443635D01*
G01X718298D02*
Y445935D01*
G01X712848Y440486D02*
X718298D01*
G01X712848Y442786D02*
Y440486D01*
G01X718298Y442786D02*
X712848D01*
G01X718298Y440486D02*
Y442786D01*
G01X727747Y449085D02*
X725447D01*
G01X718298Y445935D02*
X712848D01*
G01Y446785D02*
X718298D01*
G01X712848Y449085D02*
Y446785D01*
G01X718298Y449085D02*
X712848D01*
G01X718298Y446785D02*
Y449085D01*
G01X712848Y449934D02*
X718298D01*
G01X712848Y452234D02*
Y449934D01*
G01X718298Y452234D02*
X712848D01*
G01X718298Y449934D02*
Y452234D01*
G01X712848Y453084D02*
X718298D01*
G01X712848Y455384D02*
Y453084D01*
G01X718298Y455384D02*
X712848D01*
G01X718298Y453084D02*
Y455384D01*
G01X728597Y459383D02*
X734047D01*
G01X728597Y461683D02*
Y459383D01*
G01X734047Y461683D02*
X728597D01*
G01X722297Y480581D02*
Y475131D01*
G01X724597D02*
Y480581D01*
G01X722297Y475131D02*
X724597D01*
G01X712820Y483262D02*
Y486462D01*
G01Y487262D02*
Y490462D01*
G01X724597Y480581D02*
X722297D01*
G01X727309Y759104D02*
X730509D01*
G01X727309Y765304D02*
Y759104D01*
G01X730509Y765304D02*
X727309D01*
G01X713088Y755561D02*
X716288D01*
G01X713088Y761761D02*
Y755561D01*
G01X716288Y761761D02*
X713088D01*
G01X716288Y755561D02*
Y761761D01*
G01X717088Y755561D02*
X720288D01*
G01X717088Y761761D02*
Y755561D01*
G01X720288Y761761D02*
X717088D01*
G01X720288Y755561D02*
Y761761D01*
G01X718373Y1243190D02*
Y1240950D01*
G01X716748Y1242163D02*
X719998D01*
G01X721093Y1228972D02*
Y1232072D01*
X720327D01*
X720020Y1231917D01*
X719790Y1231710D01*
X719598Y1231400D01*
X719445Y1231039D01*
X719407Y1230522D01*
X719445Y1230005D01*
X719598Y1229644D01*
X719790Y1229334D01*
X720020Y1229127D01*
X720327Y1228972D01*
X721093D01*
G01X716690D02*
Y1232072D01*
X718108Y1229850D01*
X716192D01*
G01X714050Y1228972D02*
X713782Y1229024D01*
X713475Y1229179D01*
X713283Y1229437D01*
X713207Y1229799D01*
X713283Y1230160D01*
X713513Y1230470D01*
X713858Y1230625D01*
X714242D01*
X714472Y1230729D01*
X714663Y1230987D01*
X714740Y1231349D01*
X714625Y1231710D01*
X714357Y1231969D01*
X714050Y1232072D01*
X713743Y1231969D01*
X713475Y1231710D01*
X713360Y1231349D01*
X713437Y1230987D01*
X713628Y1230729D01*
X713858Y1230625D01*
X714242D01*
X714587Y1230470D01*
X714817Y1230160D01*
X714893Y1229799D01*
X714817Y1229437D01*
X714625Y1229179D01*
X714318Y1229024D01*
X714050Y1228972D01*
G01X730560Y1241963D02*
X728592Y1239994D01*
G01D02*
Y1243932D01*
G01X721723Y1244719D02*
Y1239207D01*
G01D02*
X737871D01*
G01X728592Y1243932D02*
X730560Y1241963D01*
G01X737871Y1244719D02*
X721723D01*
G01X717499Y1255364D02*
Y1258564D01*
G01X727432Y1251225D02*
Y1248025D01*
G01X733632Y1251225D02*
X727432D01*
G01Y1248025D02*
X733632D01*
G01X723619Y1251756D02*
Y1254956D01*
G01X717419Y1251756D02*
X723619D01*
G01X717419Y1254956D02*
Y1251756D01*
G01X723619Y1254956D02*
X717419D01*
G01X716027Y1252175D02*
X712827D01*
G01X716027Y1245975D02*
Y1252175D01*
G01X712827Y1245975D02*
X716027D01*
G01X712827Y1252175D02*
Y1245975D01*
G01X717399Y1259964D02*
Y1271964D01*
G01X727399Y1259964D02*
X733399D01*
G01X727399Y1271964D02*
Y1259964D01*
G01X733399Y1271964D02*
X727399D01*
G01X715320Y1299562D02*
Y1302762D01*
G01Y1295562D02*
Y1298762D01*
G01X714681Y1340497D02*
X716921D01*
G01X715708Y1338872D02*
Y1342122D01*
G01X729799Y1354119D02*
Y1360319D01*
X726599D01*
Y1354119D01*
X729799D01*
G01X716820Y1398023D02*
Y1386023D01*
G01X722820D02*
Y1398023D01*
G01X716820Y1386023D02*
X722820D01*
G01X725226Y1398023D02*
Y1386023D01*
G01D02*
X731226D01*
G01X722820Y1398023D02*
X716820D01*
G01X731226D02*
X725226D01*
G01X722852Y1582418D02*
X726052D01*
G01X722852Y1588618D02*
Y1582418D01*
G01X726052D02*
Y1588618D01*
G01X724252Y1567893D02*
Y1571093D01*
G01X718052Y1567893D02*
X724252D01*
G01X718052Y1571093D02*
Y1567893D01*
G01X724252Y1571093D02*
X718052D01*
G01X725152Y1567893D02*
X731352D01*
G01X725152Y1571093D02*
Y1567893D01*
G01X731352Y1571093D02*
X725152D01*
G01X726052Y1588618D02*
X722852D01*
G01X721152Y1595513D02*
Y1592313D01*
G01X727352Y1595513D02*
X721152D01*
G01X727352Y1592313D02*
Y1595513D01*
G01X721152Y1592313D02*
X727352D01*
G01X725992Y1608863D02*
X722792D01*
G01Y1602663D02*
X725992D01*
G01X722792Y1608863D02*
Y1602663D01*
G01X725992D02*
Y1608863D01*
G01X713898Y1604202D02*
Y1610402D01*
G01X721712Y1602633D02*
Y1608833D01*
G01D02*
X718512D01*
G01Y1602633D02*
X721712D01*
G01X718512Y1608833D02*
Y1602633D01*
G01X717802Y1602646D02*
Y1608846D01*
X714602D01*
Y1602646D01*
X717802D01*
G01X713196Y1662242D02*
Y1665442D01*
G01X713209Y1666241D02*
Y1669441D01*
G01X735995Y50445D02*
X739195D01*
G01X735995Y56645D02*
Y50445D01*
G01X739195D02*
Y56645D01*
G01X739777Y50445D02*
X742977D01*
G01X739777Y56645D02*
Y50445D01*
G01X742977D02*
Y56645D01*
G01X730893Y50445D02*
Y56645D01*
G01X732042Y50445D02*
X735242D01*
G01X732042Y56645D02*
Y50445D01*
G01X735242D02*
Y56645D01*
G01X743874Y50445D02*
X747074D01*
G01X743874Y56645D02*
Y50445D01*
G01X739195Y56645D02*
X735995D01*
G01X742977D02*
X739777D01*
G01X735242D02*
X732042D01*
G01X747074D02*
X743874D01*
G01X729600Y76762D02*
Y82962D01*
G01X730901Y79548D02*
Y73348D01*
G01X733020Y79548D02*
X730901D01*
G01X734101Y74342D02*
Y77702D01*
G01X730901Y73348D02*
X733110D01*
G01X738201D02*
Y79548D01*
G01D02*
X736820D01*
G01X735001Y77872D02*
Y74392D01*
G01X736060Y73348D02*
X738201D01*
G01X744820Y397562D02*
Y402162D01*
G01X734620Y397562D02*
X744820D01*
G01X734620Y402162D02*
Y397562D01*
G01X744820Y402162D02*
X734620D01*
G01X736620Y409962D02*
Y406762D01*
G01X742820Y409962D02*
X736620D01*
G01X742820Y406762D02*
Y409962D01*
G01X736620Y406762D02*
X742820D01*
G01X736620Y405962D02*
Y402762D01*
G01X742820Y405962D02*
X736620D01*
G01X742820Y402762D02*
Y405962D01*
G01X736620Y402762D02*
X742820D01*
G01X738890Y411092D02*
X745090D01*
G01X738890Y414292D02*
Y411092D01*
G01X733560Y409782D02*
Y412982D01*
G01X745090Y414292D02*
X738890D01*
G01X734047Y431037D02*
Y433337D01*
G01Y459383D02*
Y461683D01*
G01X743620Y509762D02*
X746820D01*
G01X743620Y515962D02*
Y509762D01*
G01X746820Y515962D02*
X743620D01*
G01X786501Y605413D02*
G03I-22900J0D01*
G01X735309Y759104D02*
X738509D01*
G01X735309Y765304D02*
Y759104D01*
G01X738509Y765304D02*
X735309D01*
G01X738509Y759104D02*
Y765304D01*
G01X743409Y759164D02*
X746609D01*
G01X743409Y765364D02*
Y759164D01*
G01X746609Y765364D02*
X743409D01*
G01X731309Y759104D02*
X734509D01*
G01X731309Y765304D02*
Y759104D01*
G01X734509Y765304D02*
X731309D01*
G01X734509Y759104D02*
Y765304D01*
G01X730509Y759104D02*
Y765304D01*
G01X739309Y759104D02*
X742509D01*
G01X739309Y765304D02*
Y759104D01*
G01X742509Y765304D02*
X739309D01*
G01X742509Y759104D02*
Y765304D01*
G01X743443Y1237602D02*
X741017D01*
G01X730954Y1239994D02*
Y1243932D01*
G01X739023Y1239213D02*
Y1244713D01*
G01X738273Y1239213D02*
X739023D01*
G01X738273Y1244463D02*
Y1239213D01*
G01X738573D02*
Y1244713D01*
G01X737923Y1239213D02*
X738573D01*
G01X737923Y1239313D02*
Y1239213D01*
G01X737871Y1239207D02*
Y1244719D01*
G01X732669Y1235316D02*
X729469D01*
G01X732669Y1229116D02*
Y1235316D01*
G01X729469Y1229116D02*
X732669D01*
G01X729469Y1235316D02*
Y1229116D01*
G01X739023Y1244713D02*
X738523D01*
G01X737873Y1244463D02*
X738273D01*
G01X737873Y1244713D02*
Y1244463D01*
G01X738573Y1244713D02*
X737873D01*
G01X741151Y1259281D02*
Y1256081D01*
G01D02*
X747351D01*
G01X731928Y1252898D02*
Y1259098D01*
G01X728728Y1252898D02*
X731928D01*
G01X728728Y1259098D02*
Y1252898D01*
G01X735711Y1252919D02*
Y1259119D01*
G01X732511Y1252919D02*
X735711D01*
G01X732511Y1259119D02*
Y1252919D01*
G01X733632Y1248025D02*
Y1251225D01*
G01X745622Y1250607D02*
X742422D01*
G01Y1244407D02*
X745622D01*
G01X742422Y1250607D02*
Y1244407D01*
G01X741099Y1259964D02*
X747099D01*
G01X741099Y1271964D02*
Y1259964D01*
G01X747099Y1271964D02*
X741099D01*
G01X733399Y1259964D02*
Y1271964D01*
G01X747351Y1259281D02*
X741151D01*
G01X731928Y1259098D02*
X728728D01*
G01X735711Y1259119D02*
X732511D01*
G01X736588Y1362916D02*
X730588D01*
Y1350916D01*
X736588D01*
Y1362916D01*
G01X731226Y1386023D02*
Y1398023D01*
G01X730380Y1406905D02*
X742380D01*
G01X730380Y1412905D02*
Y1406905D01*
G01X742380Y1412905D02*
X730380D01*
G01X742380Y1406905D02*
Y1412905D01*
G01X731352Y1567893D02*
Y1571093D01*
G01X747877Y50445D02*
X751077D01*
G01X747877Y56645D02*
Y50445D01*
G01X751077D02*
Y56645D01*
G01X747074Y50445D02*
Y56645D01*
G01X751077D02*
X747877D01*
G01X745920Y76162D02*
Y72962D01*
G01X752120Y76162D02*
X745920D01*
G01X752120Y72962D02*
Y76162D01*
G01X745920Y72962D02*
X752120D01*
G01X758977Y271799D02*
Y274999D01*
G01X752777Y271799D02*
X758977D01*
G01X752777Y274999D02*
Y271799D01*
G01X758977Y274999D02*
X752777D01*
G01X755939Y285032D02*
X762139D01*
G01X755939Y288232D02*
Y285032D01*
G01X762139Y288232D02*
X755939D01*
G01X755435Y304995D02*
Y311195D01*
G01D02*
X752235D01*
G01D02*
Y304995D01*
G01D02*
X755435D01*
G01Y308145D02*
Y314345D01*
G01D02*
X752235D01*
G01D02*
Y308145D01*
G01D02*
X755435D01*
G01X745090Y411092D02*
Y414292D01*
G01X759120Y414812D02*
Y411612D01*
G01D02*
X765320D01*
G01X759120Y409812D02*
Y406612D01*
G01X765320Y409812D02*
X759120D01*
G01Y406612D02*
X765320D01*
G01X749778Y409519D02*
X746578D01*
G01X749778Y403319D02*
Y409519D01*
G01X746578Y403319D02*
X749778D01*
G01X746578Y409519D02*
Y403319D01*
G01X765320Y414812D02*
X759120D01*
G01Y424812D02*
Y421612D01*
G01X765320Y424812D02*
X759120D01*
G01Y421612D02*
X765320D01*
G01X759120Y419812D02*
Y416612D01*
G01X765320Y419812D02*
X759120D01*
G01Y416612D02*
X765320D01*
G01X758240Y473262D02*
X764440D01*
G01X758240Y476462D02*
Y473262D01*
G01X764440Y476462D02*
X758240D01*
G01Y471462D02*
Y468262D01*
G01X764440Y471462D02*
X758240D01*
G01Y468262D02*
X764440D01*
G01X758240Y466462D02*
Y463262D01*
G01X764440Y466462D02*
X758240D01*
G01Y463262D02*
X764440D01*
G01X758245Y503262D02*
Y500062D01*
G01X764445Y503262D02*
X758245D01*
G01Y500062D02*
X764445D01*
G01X758257Y499258D02*
Y496058D01*
G01X764457Y499258D02*
X758257D01*
G01Y496058D02*
X764457D01*
G01X746820Y509762D02*
Y515962D01*
G01X749620Y509762D02*
X752820D01*
G01X749620Y515962D02*
Y509762D01*
G01X752820D02*
Y515962D01*
G01D02*
X749620D01*
G01X751409Y759164D02*
X754609D01*
G01X751409Y765364D02*
Y759164D01*
G01X754609Y765364D02*
X751409D01*
G01X754609Y759164D02*
Y765364D01*
G01X747409Y759164D02*
X750609D01*
G01X747409Y765364D02*
Y759164D01*
G01X750609Y765364D02*
X747409D01*
G01X750609Y759164D02*
Y765364D01*
G01X746609Y759164D02*
Y765364D01*
G01X755409Y759164D02*
X758609D01*
G01X755409Y765364D02*
Y759164D01*
G01X758609Y765364D02*
X755409D01*
G01X758609Y759164D02*
Y765364D01*
G01X747351Y1256081D02*
Y1259281D01*
G01X758717Y1259172D02*
Y1255972D01*
G01D02*
X764917D01*
G01X755260Y1255162D02*
Y1258362D01*
G01X749060Y1255162D02*
X755260D01*
G01X749060Y1258362D02*
Y1255162D01*
G01X755260Y1258362D02*
X749060D01*
G01X745622Y1244407D02*
Y1250607D01*
G01X757099Y1259964D02*
X763099D01*
G01X757099Y1271964D02*
Y1259964D01*
G01X763099Y1271964D02*
X757099D01*
G01X747099Y1259964D02*
Y1271964D01*
G01X764917Y1259172D02*
X758717D01*
G01X759212Y1583383D02*
X753012D01*
G01D02*
Y1580183D01*
G01X759212D02*
Y1583383D01*
G01X753012Y1580183D02*
X759212D01*
G01X753012Y1578803D02*
Y1575603D01*
G01X759212Y1578803D02*
X753012D01*
G01X759212Y1575603D02*
Y1578803D01*
G01X753012Y1575603D02*
X759212D01*
G01X760358Y1664841D02*
Y1671041D01*
X757158D01*
Y1664841D01*
X760358D01*
G01X761070Y1671089D02*
Y1664889D01*
X764270D01*
Y1671089D01*
X761070D01*
G01X773495Y269096D02*
X789295D01*
G01X773495Y289196D02*
Y269096D01*
G01X779145Y289196D02*
X773495D01*
G01X768577Y313958D02*
Y293858D01*
G01D02*
X784377D01*
G01X762139Y285032D02*
Y288232D01*
G01X784170Y318508D02*
Y316286D01*
X784017Y315821D01*
X783710Y315511D01*
X783327Y315408D01*
X782944Y315511D01*
X782637Y315821D01*
X782484Y316286D01*
Y318508D01*
G01X780955Y316700D02*
X780687Y317061D01*
X780457Y317268D01*
X780150Y317371D01*
X779882Y317268D01*
X779690Y317061D01*
X779537Y316751D01*
X779499Y316390D01*
X779537Y316080D01*
X779690Y315770D01*
X779920Y315511D01*
X780189Y315408D01*
X780495Y315511D01*
X780764Y315821D01*
X780917Y316286D01*
X780955Y316803D01*
X780879Y317475D01*
X780764Y317836D01*
X780572Y318198D01*
X780304Y318456D01*
X780035Y318508D01*
X779767Y318405D01*
X779575Y318146D01*
G01X777204Y315408D02*
X777127Y316080D01*
X777012Y316648D01*
X776859Y317165D01*
X776667Y317733D01*
X776360Y318508D01*
X777894D01*
G01X778727Y313958D02*
X776477Y311708D01*
G01D02*
X774227Y313958D01*
G01D02*
X768577D01*
G01X765320Y411612D02*
Y414812D01*
G01Y406612D02*
Y409812D01*
G01X774120Y421612D02*
X780320D01*
G01X774120Y424812D02*
Y421612D01*
G01X780320Y424812D02*
X774120D01*
G01X765320Y421612D02*
Y424812D01*
G01Y416612D02*
Y419812D01*
G01X774120Y416612D02*
X780320D01*
G01X774120Y419812D02*
Y416612D01*
G01X780320Y419812D02*
X774120D01*
G01X774213Y434265D02*
Y431065D01*
G01X780413Y434265D02*
X774213D01*
G01Y431065D02*
X780413D01*
G01X764440Y473262D02*
Y476462D01*
G01Y468262D02*
Y471462D01*
G01Y463262D02*
Y466462D01*
G01X773240Y473262D02*
X779440D01*
G01X773240Y476462D02*
Y473262D01*
G01X779440Y476462D02*
X773240D01*
G01X773208Y486402D02*
Y483202D01*
G01X779408Y486402D02*
X773208D01*
G01Y483202D02*
X779408D01*
G01X773240Y490462D02*
Y487262D01*
G01X779440Y490462D02*
X773240D01*
G01Y487262D02*
X779440D01*
G01X764445Y500062D02*
Y503262D01*
G01X764457Y496058D02*
Y499258D01*
G01X765587Y754779D02*
Y751579D01*
G01X771787D02*
Y754779D01*
G01X765587Y751579D02*
X771787D01*
G01X780917Y769996D02*
Y767774D01*
X780764Y767309D01*
X780457Y766999D01*
X780074Y766896D01*
X779691Y766999D01*
X779384Y767309D01*
X779231Y767774D01*
Y769996D01*
G01X777702Y769479D02*
X777472Y769789D01*
X777204Y769944D01*
X776897Y769996D01*
X776514Y769893D01*
X776246Y769634D01*
X776169Y769324D01*
X776207Y769014D01*
X776361Y768756D01*
X777127Y768239D01*
X777472Y767878D01*
X777702Y767361D01*
X777779Y766896D01*
X776169D01*
G01X774717Y767516D02*
X774487Y767154D01*
X774181Y766948D01*
X773836Y766896D01*
X773529Y766948D01*
X773222Y767206D01*
X773031Y767516D01*
X772992Y767826D01*
X773069Y768188D01*
X773337Y768446D01*
X773606Y768549D01*
X773951D01*
G01X773606D02*
X773376Y768704D01*
X773184Y768963D01*
X773107Y769273D01*
X773184Y769583D01*
X773376Y769841D01*
X773721Y769996D01*
X774066Y769944D01*
X774411Y769738D01*
G01X769324Y756565D02*
X781124D01*
G01X769324Y765227D02*
Y756565D01*
G01X781124Y765227D02*
X769324D01*
G01X767507Y759955D02*
Y763155D01*
G01X761307Y759955D02*
X767507D01*
G01X761307Y763155D02*
Y759955D01*
G01X767507Y763155D02*
X761307D01*
G01X771787Y754779D02*
X765587D01*
G01X770699Y1258564D02*
Y1255364D01*
G01X776899Y1258564D02*
X770699D01*
G01X776899Y1255364D02*
Y1258564D01*
G01X770699Y1255364D02*
X776899D01*
G01X776768Y1251677D02*
X782968D01*
G01X776768Y1254877D02*
Y1251677D01*
G01X782968Y1254877D02*
X776768D01*
G01X764917Y1255972D02*
Y1259172D01*
G01X774170Y1250612D02*
X770970D01*
G01X774170Y1244412D02*
Y1250612D01*
G01X770970Y1244412D02*
X774170D01*
G01X770970Y1250612D02*
Y1244412D01*
G01X776799Y1259964D02*
Y1271964D01*
G01X770799Y1259964D02*
X776799D01*
G01X770799Y1271964D02*
Y1259964D01*
G01X776799Y1271964D02*
X770799D01*
G01X763099Y1259964D02*
Y1271964D01*
G01X763588Y1583601D02*
X766788D01*
G01X763588Y1589801D02*
Y1583601D01*
G01X766788D02*
Y1589801D01*
G01D02*
X763588D01*
G01X770314Y1664841D02*
Y1671041D01*
X767114D01*
Y1664841D01*
X770314D01*
G01X1086083Y1787213D02*
Y1668906D01*
X771477D01*
Y1787213D01*
X1086083D01*
G01X783603Y182271D02*
G03X837186Y204724I22087J22453D01*
G01X802861Y236093D02*
G03X791804Y232994I2829J-31368D01*
G01X789295Y269096D02*
Y289196D01*
G01X795503Y293302D02*
Y291080D01*
X795350Y290615D01*
X795043Y290305D01*
X794660Y290202D01*
X794277Y290305D01*
X793970Y290615D01*
X793817Y291080D01*
Y293302D01*
G01X792288Y292785D02*
X792058Y293095D01*
X791790Y293250D01*
X791483Y293302D01*
X791100Y293199D01*
X790832Y292940D01*
X790755Y292630D01*
X790793Y292320D01*
X790947Y292062D01*
X791713Y291545D01*
X792058Y291184D01*
X792288Y290667D01*
X792365Y290202D01*
X790755D01*
G01X789188Y292785D02*
X788958Y293095D01*
X788690Y293250D01*
X788383Y293302D01*
X788000Y293199D01*
X787732Y292940D01*
X787655Y292630D01*
X787693Y292320D01*
X787847Y292062D01*
X788613Y291545D01*
X788958Y291184D01*
X789188Y290667D01*
X789265Y290202D01*
X787655D01*
G01X786203Y290822D02*
X785973Y290460D01*
X785667Y290254D01*
X785322Y290202D01*
X785015Y290254D01*
X784708Y290512D01*
X784517Y290822D01*
X784478Y291132D01*
X784555Y291494D01*
X784823Y291752D01*
X785092Y291855D01*
X785437D01*
G01X785092D02*
X784862Y292010D01*
X784670Y292269D01*
X784593Y292579D01*
X784670Y292889D01*
X784862Y293147D01*
X785207Y293302D01*
X785552Y293250D01*
X785897Y293044D01*
G01X781395Y286946D02*
X779145Y289196D01*
G01X783645D02*
X781395Y286946D01*
G01X789295Y289196D02*
X783645D01*
G01X784377Y293858D02*
Y313958D01*
G01D02*
X778727D01*
G01X780320Y421612D02*
Y424812D01*
G01Y416612D02*
Y419812D01*
G01X780413Y431065D02*
Y434265D01*
G01X786907Y434155D02*
Y430955D01*
G01X793107Y434155D02*
X786907D01*
G01X793107Y430955D02*
Y434155D01*
G01X786907Y430955D02*
X793107D01*
G01X779440Y473262D02*
Y476462D01*
G01X779408Y483202D02*
Y486402D01*
G01X779440Y487262D02*
Y490462D01*
G01X781124Y756565D02*
Y765227D01*
G01X792024Y762396D02*
X798224D01*
G01X792024Y765596D02*
Y762396D01*
G01X798224Y765596D02*
X792024D01*
G01X790627Y758055D02*
Y761255D01*
G01X784427Y758055D02*
X790627D01*
G01X784427Y761255D02*
Y758055D01*
G01X790627Y761255D02*
X784427D01*
G01X792027Y756855D02*
X798227D01*
G01X792027Y760055D02*
Y756855D01*
G01X798227Y760055D02*
X792027D01*
G01X790627Y762255D02*
Y765455D01*
G01X784427Y762255D02*
X790627D01*
G01X784427Y765455D02*
Y762255D01*
G01X790627Y765455D02*
X784427D01*
G01X793285Y1252794D02*
Y1258994D01*
G01X790085Y1252794D02*
X793285D01*
G01X790085Y1258994D02*
Y1252794D01*
G01X782968Y1251677D02*
Y1254877D01*
G01X792799Y1259964D02*
Y1271964D01*
G01X786799Y1259964D02*
X792799D01*
G01X786799Y1271964D02*
Y1259964D01*
G01X792799Y1271964D02*
X786799D01*
G01X793285Y1258994D02*
X790085D01*
G01X809820Y144662D02*
X806620D01*
G01X809820Y138462D02*
Y144662D01*
G01X806620Y138462D02*
X809820D01*
G01X806620Y144662D02*
Y138462D01*
G01X797420Y140862D02*
Y137662D01*
G01X803620Y140862D02*
X797420D01*
G01X803620Y137662D02*
Y140862D01*
G01X797420Y137662D02*
X803620D01*
G01X797420Y145862D02*
Y142662D01*
G01X803620Y145862D02*
X797420D01*
G01X803620Y142662D02*
Y145862D01*
G01X797420Y142662D02*
X803620D01*
G01X808564Y278420D02*
Y275220D01*
G01X814764Y278420D02*
X808564D01*
G01Y275220D02*
X814764D01*
G01X808618Y285911D02*
Y282711D01*
G01X814818Y285911D02*
X808618D01*
G01Y282711D02*
X814818D01*
G01X802599Y293888D02*
Y297088D01*
G01X796399Y293888D02*
X802599D01*
G01X796399Y297088D02*
Y293888D01*
G01X802599Y297088D02*
X796399D01*
G01X805769Y311173D02*
Y314373D01*
G01X799569Y311173D02*
X805769D01*
G01X799569Y314373D02*
Y311173D01*
G01X805769Y314373D02*
X799569D01*
G01X802499Y301588D02*
Y304788D01*
G01X796299Y301588D02*
X802499D01*
G01X796299Y304788D02*
Y301588D01*
G01X802499Y304788D02*
X796299D01*
G01X796290Y309662D02*
Y306462D01*
G01X802490Y309662D02*
X796290D01*
G01X802490Y306462D02*
Y309662D01*
G01X796290Y306462D02*
X802490D01*
G01X807243Y424029D02*
X810443D01*
G01X807243Y430229D02*
Y424029D01*
G01X810443Y430229D02*
X807243D01*
G01X807197Y431825D02*
X810397D01*
G01X807197Y438025D02*
Y431825D01*
G01X810397Y438025D02*
X807197D01*
G01X807987Y765715D02*
Y756915D01*
G01Y765715D02*
X813787D01*
G01X807987Y756915D02*
X821587D01*
G01X806777Y762315D02*
Y765515D01*
G01X800577Y762315D02*
X806777D01*
G01X800577Y765515D02*
Y762315D01*
G01X806777Y765515D02*
X800577D01*
G01X806777Y758065D02*
Y761265D01*
G01X800577Y758065D02*
X806777D01*
G01X800577Y761265D02*
Y758065D01*
G01X806777Y761265D02*
X800577D01*
G01X798224Y762396D02*
Y765596D01*
G01X798227Y756855D02*
Y760055D01*
G01X800399Y1258564D02*
Y1255364D01*
G01X806599Y1258564D02*
X800399D01*
G01X806599Y1255364D02*
Y1258564D01*
G01X800399Y1255364D02*
X806599D01*
G01X806233Y1251912D02*
X812433D01*
G01X806233Y1255112D02*
Y1251912D01*
G01X812433Y1255112D02*
X806233D01*
G01X804716Y1248717D02*
X801516D01*
G01X804716Y1242517D02*
Y1248717D01*
G01X801516Y1242517D02*
X804716D01*
G01X801516Y1248717D02*
Y1242517D01*
G01X806499Y1259964D02*
Y1271964D01*
G01X800499Y1259964D02*
X806499D01*
G01X800499Y1271964D02*
Y1259964D01*
G01X806499Y1271964D02*
X800499D01*
G01X872736Y1420330D02*
G03I-31496J0D01*
G01X806697Y1586683D02*
X809897D01*
G01X806697Y1592883D02*
Y1586683D01*
G01X809897Y1592883D02*
X806697D01*
G01X809897Y1586683D02*
Y1592883D01*
G01X816620Y4383D02*
X816310Y4575D01*
X816103Y4805D01*
X816000Y5073D01*
X816103Y5380D01*
X816310Y5610D01*
X816620Y5840D01*
X817033Y5917D01*
X819100D01*
G01X816000Y8173D02*
X816672Y8250D01*
X817240Y8365D01*
X817757Y8518D01*
X818325Y8710D01*
X819100Y9017D01*
Y7483D01*
G01X816000Y11810D02*
X819100D01*
X816878Y10392D01*
Y12308D01*
G01X822720Y144062D02*
X819520D01*
G01X822720Y137862D02*
Y144062D01*
G01X819520Y137862D02*
X822720D01*
G01X819520Y144062D02*
Y137862D01*
G01X826100Y288998D02*
Y268898D01*
G01D02*
X831750D01*
G01X814764Y275220D02*
Y278420D01*
G01X816099Y294138D02*
X831899D01*
G01X816099Y314238D02*
Y294138D01*
G01X841900Y288998D02*
X826100D01*
G01X814818Y282711D02*
Y285911D01*
G01X831692Y318788D02*
Y316566D01*
X831539Y316101D01*
X831232Y315791D01*
X830849Y315688D01*
X830466Y315791D01*
X830159Y316101D01*
X830006Y316566D01*
Y318788D01*
G01X828477Y318271D02*
X828247Y318581D01*
X827979Y318736D01*
X827672Y318788D01*
X827289Y318685D01*
X827021Y318426D01*
X826944Y318116D01*
X826982Y317806D01*
X827136Y317548D01*
X827902Y317031D01*
X828247Y316670D01*
X828477Y316153D01*
X828554Y315688D01*
X826944D01*
G01X825377Y318271D02*
X825147Y318581D01*
X824879Y318736D01*
X824572Y318788D01*
X824189Y318685D01*
X823921Y318426D01*
X823844Y318116D01*
X823882Y317806D01*
X824036Y317548D01*
X824802Y317031D01*
X825147Y316670D01*
X825377Y316153D01*
X825454Y315688D01*
X823844D01*
G01X822277Y318271D02*
X822047Y318581D01*
X821779Y318736D01*
X821472Y318788D01*
X821089Y318685D01*
X820821Y318426D01*
X820744Y318116D01*
X820782Y317806D01*
X820936Y317548D01*
X821702Y317031D01*
X822047Y316670D01*
X822277Y316153D01*
X822354Y315688D01*
X820744D01*
G01X821749Y314238D02*
X816099D01*
G01X823999Y311988D02*
X821749Y314238D01*
G01X826249D02*
X823999Y311988D01*
G01X810443Y424029D02*
Y430229D01*
G01X810397Y431825D02*
Y438025D01*
G01X819620Y755415D02*
Y753193D01*
X819467Y752728D01*
X819160Y752418D01*
X818777Y752315D01*
X818394Y752418D01*
X818087Y752728D01*
X817934Y753193D01*
Y755415D01*
G01X816405Y754898D02*
X816175Y755208D01*
X815907Y755363D01*
X815600Y755415D01*
X815217Y755312D01*
X814949Y755053D01*
X814872Y754743D01*
X814910Y754433D01*
X815064Y754175D01*
X815830Y753658D01*
X816175Y753297D01*
X816405Y752780D01*
X816482Y752315D01*
X814872D01*
G01X812577D02*
Y755415D01*
X813037Y754795D01*
G01Y752315D02*
X812117D01*
G01X814787Y764215D02*
X815787Y765715D01*
G01X813787D02*
X814787Y764215D01*
G01X821587Y756915D02*
Y765715D01*
G01X815787D02*
X821587D01*
G01X822767Y758615D02*
X828967D01*
G01X822767Y761815D02*
Y758615D01*
G01X828967Y761815D02*
X822767D01*
G01X822864Y762716D02*
X829064D01*
G01X822864Y765916D02*
Y762716D01*
G01X829064Y765916D02*
X822864D01*
G01X826873Y1227082D02*
Y1230182D01*
X826107D01*
X825800Y1230027D01*
X825570Y1229820D01*
X825378Y1229510D01*
X825225Y1229149D01*
X825187Y1228632D01*
X825225Y1228115D01*
X825378Y1227754D01*
X825570Y1227444D01*
X825800Y1227237D01*
X826107Y1227082D01*
X826873D01*
G01X822470D02*
Y1230182D01*
X823888Y1227960D01*
X821972D01*
G01X820482Y1227444D02*
X820213Y1227185D01*
X819907Y1227082D01*
X819600Y1227185D01*
X819332Y1227495D01*
X819140Y1227960D01*
X819063Y1228425D01*
Y1228994D01*
X819140Y1229459D01*
X819332Y1229872D01*
X819562Y1230079D01*
X819830Y1230182D01*
X820137Y1230079D01*
X820367Y1229872D01*
X820520Y1229562D01*
X820597Y1229149D01*
X820520Y1228787D01*
X820328Y1228425D01*
X820098Y1228219D01*
X819830Y1228167D01*
X819523Y1228270D01*
X819293Y1228529D01*
X819063Y1228994D01*
G01X826840Y1244155D02*
Y1241729D01*
G01X821710Y1242012D02*
Y1248212D01*
G01X818510Y1242012D02*
X821710D01*
G01X818510Y1248212D02*
Y1242012D01*
G01X812433Y1251912D02*
Y1255112D01*
G01X821001Y1257594D02*
X817801D01*
G01X821001Y1251394D02*
Y1257594D01*
G01X817801Y1251394D02*
X821001D01*
G01X817801Y1257594D02*
Y1251394D01*
G01X821710Y1248212D02*
X818510D01*
G01X822499Y1259964D02*
Y1271964D01*
G01X816499Y1259964D02*
X822499D01*
G01X816499Y1271964D02*
Y1259964D01*
G01X822499Y1271964D02*
X816499D01*
G01X838870Y200D02*
Y16800D01*
X829270D01*
Y200D01*
X838870D01*
G01X843320Y217462D02*
X840120D01*
G01Y211262D02*
X843320D01*
G01X840120Y217462D02*
Y211262D01*
G01X839100Y227752D02*
X835900D01*
G01X839100Y221552D02*
Y227752D01*
G01X835900Y221552D02*
X839100D01*
G01X835900Y227752D02*
Y221552D01*
G01X831845Y221618D02*
X835045D01*
G01X831845Y227818D02*
Y221618D01*
G01X835045Y227818D02*
X831845D01*
G01X835045Y221618D02*
Y227818D01*
G01X841120Y218762D02*
X847320D01*
G01X841120Y221962D02*
Y218762D01*
G01X847320Y221962D02*
X841120D01*
G01X835723Y266166D02*
Y263944D01*
X835570Y263479D01*
X835263Y263169D01*
X834880Y263066D01*
X834497Y263169D01*
X834190Y263479D01*
X834037Y263944D01*
Y266166D01*
G01X832508Y264358D02*
X832240Y264719D01*
X832010Y264926D01*
X831703Y265029D01*
X831435Y264926D01*
X831243Y264719D01*
X831090Y264409D01*
X831052Y264048D01*
X831090Y263738D01*
X831243Y263428D01*
X831473Y263169D01*
X831742Y263066D01*
X832048Y263169D01*
X832317Y263479D01*
X832470Y263944D01*
X832508Y264461D01*
X832432Y265133D01*
X832317Y265494D01*
X832125Y265856D01*
X831857Y266114D01*
X831588Y266166D01*
X831320Y266063D01*
X831128Y265804D01*
G01X828680Y263066D02*
X828412Y263118D01*
X828105Y263273D01*
X827913Y263531D01*
X827837Y263893D01*
X827913Y264254D01*
X828143Y264564D01*
X828488Y264719D01*
X828872D01*
X829102Y264823D01*
X829293Y265081D01*
X829370Y265443D01*
X829255Y265804D01*
X828987Y266063D01*
X828680Y266166D01*
X828373Y266063D01*
X828105Y265804D01*
X827990Y265443D01*
X828067Y265081D01*
X828258Y264823D01*
X828488Y264719D01*
X828872D01*
X829217Y264564D01*
X829447Y264254D01*
X829523Y263893D01*
X829447Y263531D01*
X829255Y263273D01*
X828948Y263118D01*
X828680Y263066D01*
G01X841900Y268898D02*
Y288998D01*
G01X831750Y268898D02*
X834000Y271148D01*
G01D02*
X836250Y268898D01*
G01D02*
X841900D01*
G01X831899Y294138D02*
Y314238D01*
G01D02*
X826249D01*
G01X841370Y755205D02*
Y752983D01*
X841217Y752518D01*
X840910Y752208D01*
X840527Y752105D01*
X840144Y752208D01*
X839837Y752518D01*
X839684Y752983D01*
Y755205D01*
G01X838155Y754688D02*
X837925Y754998D01*
X837657Y755153D01*
X837350Y755205D01*
X836967Y755102D01*
X836699Y754843D01*
X836622Y754533D01*
X836660Y754223D01*
X836814Y753965D01*
X837580Y753448D01*
X837925Y753087D01*
X838155Y752570D01*
X838232Y752105D01*
X836622D01*
G01X835055Y754688D02*
X834825Y754998D01*
X834557Y755153D01*
X834250Y755205D01*
X833867Y755102D01*
X833599Y754843D01*
X833522Y754533D01*
X833560Y754223D01*
X833714Y753965D01*
X834480Y753448D01*
X834825Y753087D01*
X835055Y752570D01*
X835132Y752105D01*
X833522D01*
G01X837057Y764435D02*
X838057Y765935D01*
G01X836057D02*
X837057Y764435D01*
G01X830257Y765935D02*
Y757135D01*
G01Y765935D02*
X836057D01*
G01X838057D02*
X843857D01*
G01X830257Y757135D02*
X843857D01*
G01X828967Y758615D02*
Y761815D01*
G01X829064Y762716D02*
Y765916D01*
G01X838797Y768425D02*
X844997D01*
G01X838797Y771625D02*
Y768425D01*
G01X844997Y771625D02*
X838797D01*
G01X831980Y1233261D02*
X834220D01*
G01X833007Y1231636D02*
Y1234886D01*
G01X830451Y1236611D02*
X835963D01*
G01X830451Y1252759D02*
Y1236611D01*
G01X835963D02*
Y1252759D01*
G01X842251Y1241486D02*
X839051D01*
G01X842251Y1235286D02*
Y1241486D01*
G01X839051Y1235286D02*
X842251D01*
G01X839051Y1241486D02*
Y1235286D01*
G01X833207Y1245448D02*
X835176Y1243480D01*
G01X831238D02*
X833207Y1245448D01*
G01X835176Y1243480D02*
X831238D01*
G01X835176Y1245842D02*
X831238D01*
G01X830457Y1253911D02*
Y1253411D01*
G01X835957Y1253911D02*
X830457D01*
G01X835957Y1253161D02*
Y1253911D01*
G01X830707Y1253161D02*
X835957D01*
G01X830707Y1252761D02*
Y1253161D01*
G01X830457Y1252761D02*
X830707D01*
G01X830457Y1253461D02*
Y1252761D01*
G01X835957Y1253461D02*
X830457D01*
G01X835957Y1252811D02*
Y1253461D01*
G01X835857Y1252811D02*
X835957D01*
G01X835963Y1252759D02*
X830451D01*
G01X830099Y1258564D02*
Y1255364D01*
G01X836299Y1258564D02*
X830099D01*
G01X836299Y1255364D02*
Y1258564D01*
G01X830099Y1255364D02*
X836299D01*
G01X837770Y1250792D02*
X843970D01*
G01X837770Y1253992D02*
Y1250792D01*
G01X843970Y1253992D02*
X837770D01*
G01X836199Y1259964D02*
Y1271964D01*
G01X830199Y1259964D02*
X836199D01*
G01X830199Y1271964D02*
Y1259964D01*
G01X836199Y1271964D02*
X830199D01*
G01X837246Y1259964D02*
X843246D01*
G01X837246Y1271964D02*
Y1259964D01*
G01X843246Y1271964D02*
X837246D01*
G01X854220Y214762D02*
Y217962D01*
G01X848020Y214762D02*
X854220D01*
G01X848020Y217962D02*
Y214762D01*
G01X854320Y207762D02*
Y210962D01*
G01X848120Y207762D02*
X854320D01*
G01X848120Y210962D02*
Y207762D01*
G01X854320Y210962D02*
X848120D01*
G01X843320Y211262D02*
Y217462D01*
G01X854220Y217962D02*
X848020D01*
G01X847320Y218762D02*
Y221962D01*
G01X858465Y270820D02*
Y267620D01*
G01X864665Y270820D02*
X858465D01*
G01Y267620D02*
X864665D01*
G01X848131Y303142D02*
Y299942D01*
G01X854331Y303142D02*
X848131D01*
G01X854331Y299942D02*
Y303142D01*
G01X848131Y299942D02*
X854331D01*
G01X848290Y310452D02*
Y307252D01*
G01X854490Y310452D02*
X848290D01*
G01X854490Y307252D02*
Y310452D01*
G01X848290Y307252D02*
X854490D01*
G01X843857Y757135D02*
Y765935D01*
G01X844997Y768425D02*
Y771625D01*
G01X846277Y771527D02*
Y759323D01*
X862277D01*
Y771527D01*
X846277D01*
G01X862870Y776392D02*
Y774170D01*
X862717Y773705D01*
X862410Y773395D01*
X862027Y773292D01*
X861644Y773395D01*
X861337Y773705D01*
X861184Y774170D01*
Y776392D01*
G01X858927Y773292D02*
Y776392D01*
X859387Y775772D01*
G01Y773292D02*
X858467D01*
G01X856555Y774584D02*
X856287Y774945D01*
X856057Y775152D01*
X855750Y775255D01*
X855482Y775152D01*
X855290Y774945D01*
X855137Y774635D01*
X855099Y774274D01*
X855137Y773964D01*
X855290Y773654D01*
X855520Y773395D01*
X855789Y773292D01*
X856095Y773395D01*
X856364Y773705D01*
X856517Y774170D01*
X856555Y774687D01*
X856479Y775359D01*
X856364Y775720D01*
X856172Y776082D01*
X855904Y776340D01*
X855635Y776392D01*
X855367Y776289D01*
X855175Y776030D01*
G01X848167Y1238376D02*
X851367D01*
G01X848167Y1244576D02*
Y1238376D01*
G01X851367D02*
Y1244576D01*
G01X843970Y1250792D02*
Y1253992D01*
G01X848871Y1258323D02*
X845671D01*
G01X848871Y1252123D02*
Y1258323D01*
G01X845671Y1252123D02*
X848871D01*
G01X845671Y1258323D02*
Y1252123D01*
G01X851367Y1251390D02*
X848167D01*
G01X851367Y1245190D02*
Y1251390D01*
G01X848167Y1245190D02*
X851367D01*
G01X848167Y1251390D02*
Y1245190D01*
G01X851367Y1244576D02*
X848167D01*
G01X843246Y1259964D02*
Y1271964D01*
G01X848815Y1586147D02*
X852015D01*
G01X848815Y1592347D02*
Y1586147D01*
G01X852015Y1592347D02*
X848815D01*
G01X852015Y1586147D02*
Y1592347D01*
G01X864665Y267620D02*
Y270820D01*
G01X895351Y186664D02*
Y189764D01*
G01X893741D02*
Y186664D01*
G01Y188214D02*
X895351D01*
G01X891523Y186664D02*
X891446Y187336D01*
X891331Y187904D01*
X891178Y188421D01*
X890986Y188989D01*
X890679Y189764D01*
X892213D01*
G01X888423Y186664D02*
X888346Y187336D01*
X888231Y187904D01*
X888078Y188421D01*
X887886Y188989D01*
X887579Y189764D01*
X889113D01*
G01X890881Y508475D02*
Y505275D01*
G01X897081Y508475D02*
X890881D01*
G01Y505275D02*
X897081D01*
G01X890732Y1586543D02*
X893932D01*
G01X890732Y1592743D02*
Y1586543D01*
G01X893932Y1592743D02*
X890732D01*
G01X901265Y337054D02*
G03X932071Y290334I27474J-15401D01*
G01X896487Y461312D02*
X899687D01*
G01X896487Y467512D02*
Y461312D01*
G01X899687D02*
Y467512D01*
G01X901275Y461312D02*
X904475D01*
G01X901275Y467512D02*
Y461312D01*
G01X904475D02*
Y467512D01*
G01X904193Y484304D02*
Y474304D01*
G01D02*
X908793D01*
G01X899687Y467512D02*
X896487D01*
G01X904475D02*
X901275D01*
G01X905820Y464462D02*
X909020D01*
G01X905820Y470662D02*
Y464462D01*
G01X909020Y470662D02*
X905820D01*
G01X902760Y492922D02*
X898160D01*
G01Y487822D02*
X902760D01*
G01X898160Y498022D02*
Y487822D01*
G01X902760D02*
Y498022D01*
G01X904193Y479804D02*
X908793D01*
G01X904193Y484304D02*
X908793D01*
G01X904193Y478804D02*
X908793D01*
G01X903410Y489187D02*
X906610D01*
G01X903410Y495387D02*
Y489187D01*
G01X906610D02*
Y495387D01*
G01X907484Y495211D02*
Y492011D01*
G01D02*
X913684D01*
G01X902760Y498022D02*
X898160D01*
G01X906610Y495387D02*
X903410D01*
G01X897081Y505275D02*
Y508475D01*
G01X901474Y508948D02*
Y505748D01*
G01X907674Y508948D02*
X901474D01*
G01Y505748D02*
X907674D01*
G01X913684Y495211D02*
X907484D01*
G01X901980Y501717D02*
Y498517D01*
G01X908180Y501717D02*
X901980D01*
G01Y498517D02*
X908180D01*
G01X901980Y505231D02*
Y502031D01*
G01X908180Y505231D02*
X901980D01*
G01Y502031D02*
X908180D01*
G01X893932Y1586543D02*
Y1592743D01*
G01X960235Y321653D02*
G03X923312Y352678I-31496J0D01*
G01X917069Y478094D02*
Y473494D01*
G01D02*
X927269D01*
G01X911101Y483804D02*
Y473804D01*
G01X915701D02*
Y483804D01*
G01X915601Y473804D02*
X915701D01*
G01X911101D02*
X915701D01*
G01X908793Y474304D02*
Y484304D01*
G01X908693Y474304D02*
X908793D01*
G01X909920Y464462D02*
X913120D01*
G01X909920Y470662D02*
Y464462D01*
G01X913120Y470662D02*
X909920D01*
G01X913120Y464462D02*
Y470662D01*
G01X909020Y464462D02*
Y470662D01*
G01X922482Y484312D02*
X927082D01*
G01Y489412D02*
X922482D01*
G01Y479212D02*
X927082D01*
G01X922482Y489412D02*
Y479212D01*
G01X917215D02*
X921815D01*
G01X917215Y489412D02*
Y479212D01*
G01X921815Y489412D02*
X917215D01*
G01X921815Y479212D02*
Y489412D01*
G01X927269Y478094D02*
X917069D01*
G01X911101Y479304D02*
X915701D01*
G01X911101Y483804D02*
X915701D01*
G01X911101Y478304D02*
X915701D01*
G01X913684Y492011D02*
Y495211D01*
G01X914511Y507427D02*
X917711D01*
G01X914511Y513627D02*
Y507427D01*
G01X917711D02*
Y513627D01*
G01X907674Y505748D02*
Y508948D01*
G01X908180Y498517D02*
Y501717D01*
G01Y502031D02*
Y505231D01*
G01X917711Y513627D02*
X914511D01*
G01X919549Y518456D02*
X922749D01*
G01X919549Y524656D02*
Y518456D01*
G01X922749Y524656D02*
X919549D01*
G01X922749Y518456D02*
Y524656D01*
G01X926361Y524639D02*
X923161D01*
G01Y518439D02*
X926361D01*
G01X923161Y524639D02*
Y518439D01*
G01X917750Y977932D02*
X920950D01*
G01X917750Y984132D02*
Y977932D01*
G01X920950D02*
Y984132D01*
G01X917800Y987842D02*
Y984642D01*
G01X924000Y987842D02*
X917800D01*
G01Y984642D02*
X924000D01*
G01X917700Y988552D02*
X920900D01*
G01X917700Y994752D02*
Y988552D01*
G01X920900Y994752D02*
X917700D01*
G01X920900Y988552D02*
Y994752D01*
G01X920950Y984132D02*
X917750D01*
G01X920720Y1662262D02*
X923920D01*
G01X920720Y1668462D02*
Y1662262D01*
G01X916700Y1668500D02*
Y1662300D01*
X919900D01*
Y1668500D01*
X916700D01*
G01X916100Y1662300D02*
Y1668500D01*
X912900D01*
Y1662300D01*
X916100D01*
G01X923920Y1668462D02*
X920720D01*
G01X974007Y1671560D02*
Y1679060D01*
X971767D01*
X971020Y1678685D01*
X970460Y1677810D01*
X970273Y1676810D01*
X970460Y1675810D01*
X970927Y1675060D01*
X971767Y1674685D01*
X974007D01*
G01X966507Y1671560D02*
Y1679060D01*
X964173D01*
X963427Y1678685D01*
X962960Y1678185D01*
X962773Y1677185D01*
X962960Y1676185D01*
X963520Y1675560D01*
X964173Y1675185D01*
X966507D01*
G01X964173D02*
X962773Y1671560D01*
G01X955273D02*
X959007D01*
Y1679060D01*
X955273D01*
G01X956767Y1675435D02*
X959007D01*
G01X951600Y1672560D02*
X950853Y1671935D01*
X950013Y1671560D01*
X949267D01*
X948520Y1671935D01*
X947960Y1672560D01*
X947680Y1673435D01*
X947867Y1674310D01*
X948333Y1675060D01*
X949173Y1675560D01*
X950293Y1675810D01*
X950947Y1676310D01*
X951227Y1677185D01*
X951040Y1678060D01*
X950573Y1678685D01*
X949920Y1679060D01*
X949267D01*
X948613Y1678810D01*
X948053Y1678185D01*
G01X944100Y1672560D02*
X943353Y1671935D01*
X942513Y1671560D01*
X941767D01*
X941020Y1671935D01*
X940460Y1672560D01*
X940180Y1673435D01*
X940367Y1674310D01*
X940833Y1675060D01*
X941673Y1675560D01*
X942793Y1675810D01*
X943447Y1676310D01*
X943727Y1677185D01*
X943540Y1678060D01*
X943073Y1678685D01*
X942420Y1679060D01*
X941767D01*
X941113Y1678810D01*
X940553Y1678185D01*
G01X935853Y1674060D02*
X933427D01*
G01X928913Y1671560D02*
Y1679060D01*
X925367D01*
G01X926673Y1675435D02*
X928913D01*
G01X920760Y1679060D02*
X918520D01*
G01X919640D02*
Y1671560D01*
G01X920760D02*
X918520D01*
G01X912140Y1679060D02*
Y1671560D01*
G01X914287Y1679060D02*
X909993D01*
G01X943726Y166452D02*
Y169552D01*
G01X942116D02*
Y166452D01*
G01Y168002D02*
X943726D01*
G01X939898Y166452D02*
X939821Y167124D01*
X939706Y167692D01*
X939553Y168209D01*
X939361Y168777D01*
X939054Y169552D01*
X940588D01*
G01X937449Y167744D02*
X937181Y168105D01*
X936951Y168312D01*
X936644Y168415D01*
X936376Y168312D01*
X936184Y168105D01*
X936031Y167795D01*
X935993Y167434D01*
X936031Y167124D01*
X936184Y166814D01*
X936414Y166555D01*
X936683Y166452D01*
X936989Y166555D01*
X937258Y166865D01*
X937411Y167330D01*
X937449Y167847D01*
X937373Y168519D01*
X937258Y168880D01*
X937066Y169242D01*
X936798Y169500D01*
X936529Y169552D01*
X936261Y169449D01*
X936069Y169190D01*
G01X934695Y190986D02*
X928495D01*
G01X934695Y187786D02*
Y190986D01*
G01X928495Y187786D02*
X934695D01*
G01X928495Y190986D02*
Y187786D01*
G01X934895Y191786D02*
Y194986D01*
G01X928695Y191786D02*
X934895D01*
G01X928695Y194986D02*
Y191786D01*
G01X934895Y194986D02*
X928695D01*
G01X926825Y199212D02*
Y196012D01*
G01X933025Y199212D02*
X926825D01*
G01X933025Y196012D02*
Y199212D01*
G01X926825Y196012D02*
X933025D01*
G01Y200012D02*
Y203212D01*
G01X926825Y200012D02*
X933025D01*
G01X926825Y203212D02*
Y200012D01*
G01X933025Y203212D02*
X926825D01*
G01X934866Y379023D02*
X947746D01*
G01X934866D02*
Y385423D01*
G01X947746D02*
X934866D01*
G01X934994Y475011D02*
Y479611D01*
G01X929894D02*
Y475011D01*
G01X940094D02*
Y479611D01*
G01X929894Y475011D02*
X940094D01*
G01X927269Y473494D02*
Y478094D01*
G01X940094Y479611D02*
X929894D01*
G01X927082Y479212D02*
Y489412D01*
G01X934087Y490783D02*
X930887D01*
G01X934087Y484583D02*
Y490783D01*
G01X930887Y484583D02*
X934087D01*
G01X930887Y490783D02*
Y484583D01*
G01X930558Y489138D02*
X927358D01*
G01X930558Y482938D02*
Y489138D01*
G01X927358Y482938D02*
X930558D01*
G01X927358Y489138D02*
Y482938D01*
G01X939489Y492101D02*
Y495301D01*
G01X933289Y492101D02*
X939489D01*
G01X933289Y495301D02*
Y492101D01*
G01X933268Y507577D02*
Y504377D01*
G01X939468Y507577D02*
X933268D01*
G01X939468Y504377D02*
Y507577D01*
G01X933268Y504377D02*
X939468D01*
G01X933263Y503525D02*
Y500325D01*
G01X939463Y503525D02*
X933263D01*
G01X939463Y500325D02*
Y503525D01*
G01X933263Y500325D02*
X939463D01*
G01X939489Y495301D02*
X933289D01*
G01X933294Y499683D02*
Y496483D01*
G01X939494Y499683D02*
X933294D01*
G01X939494Y496483D02*
Y499683D01*
G01X933294Y496483D02*
X939494D01*
G01X936043Y510250D02*
X939243D01*
G01X936043Y516450D02*
Y510250D01*
G01X939243D02*
Y516450D01*
G01X929901Y526151D02*
X936101D01*
G01X929901Y529351D02*
Y526151D01*
G01X936101D02*
Y526752D01*
G01X932951Y526151D02*
Y529351D01*
G01X926751Y526151D02*
X932951D01*
G01X926751Y527142D02*
Y526151D01*
G01X929065Y513698D02*
Y510498D01*
G01X935265D02*
Y513698D01*
G01X929065Y510498D02*
X935265D01*
G01Y513698D02*
X929065D01*
G01X938370Y518588D02*
X941570D01*
G01Y524788D02*
X938370D01*
G01D02*
Y518588D01*
G01X926361Y518439D02*
Y524639D01*
G01X939243Y516450D02*
X936043D01*
G01X937770Y519748D02*
Y522948D01*
G01X931570Y519748D02*
X937770D01*
G01X931570Y522948D02*
Y519748D01*
G01X937770Y522948D02*
X931570D01*
G01X929993Y523191D02*
X926793D01*
G01X929993Y516991D02*
Y523191D01*
G01X926793Y516991D02*
X929993D01*
G01X926793Y523191D02*
Y516991D01*
G01X930800Y529351D02*
X929901D01*
G01X936101D02*
X932120D01*
G01X936101Y528642D02*
Y529351D01*
G01X930800D02*
X927360D01*
G01X932951D02*
X932120D01*
G01X929978Y534677D02*
Y531477D01*
G01X936178Y534677D02*
X929978D01*
G01X934280Y531477D02*
X936178D01*
G01X929978D02*
X931720D01*
G01X936178Y533832D02*
Y534677D01*
G01Y531477D02*
Y532212D01*
G01X933028Y534677D02*
X926828D01*
G01D02*
Y532912D01*
G01X933028Y532252D02*
Y534677D01*
G01X927360Y531477D02*
X931720D01*
G01X931130Y970642D02*
Y964242D01*
G01D02*
X944010D01*
G01X931261Y972162D02*
X943261D01*
G01X931261Y978162D02*
Y972162D01*
G01X943261Y978162D02*
X931261D01*
G01X944010Y970642D02*
X931130D01*
G01X924780Y978082D02*
X927980D01*
G01X924780Y984282D02*
Y978082D01*
G01X927980D02*
Y984282D01*
G01X935740Y978862D02*
Y982062D01*
G01X929540Y978862D02*
X935740D01*
G01X929540Y982062D02*
Y978862D01*
G01X935740Y982062D02*
X929540D01*
G01X924000Y984642D02*
Y987842D01*
G01X927980Y984282D02*
X924780D01*
G01X935878Y984543D02*
Y987743D01*
G01X929678Y984543D02*
X935878D01*
G01X929678Y987743D02*
Y984543D01*
G01X935878Y987743D02*
X929678D01*
G01X935620Y995672D02*
X932420D01*
G01X935620Y989472D02*
Y995672D01*
G01X932420Y989472D02*
X935620D01*
G01X932420Y995672D02*
Y989472D01*
G01X939820Y1662162D02*
Y1668362D01*
G01X936620Y1662162D02*
X939820D01*
G01X936620Y1668362D02*
Y1662162D01*
G01X927720Y1662262D02*
Y1668462D01*
G01X924520Y1662262D02*
X927720D01*
G01X924520Y1668462D02*
Y1662262D01*
G01X923920D02*
Y1668462D01*
G01X935579Y1662227D02*
Y1668427D01*
G01X932379Y1662227D02*
X935579D01*
G01X932379Y1668427D02*
Y1662227D01*
G01X931579Y1662262D02*
Y1668462D01*
G01X928379Y1662262D02*
X931579D01*
G01X928379Y1668462D02*
Y1662262D01*
G01X939820Y1668362D02*
X936620D01*
G01X927720Y1668462D02*
X924520D01*
G01X935579Y1668427D02*
X932379D01*
G01X931579Y1668462D02*
X928379D01*
G01X955361Y304822D02*
G03X960235Y321653I-26622J16831D01*
G01X954408Y378966D02*
X959008D01*
G01X954408Y389166D02*
Y378966D01*
G01X949614Y378962D02*
X954214D01*
G01X949614Y389162D02*
Y378962D01*
G01X954214D02*
Y389162D01*
G01X947746Y379023D02*
Y385423D01*
G01X959008Y384066D02*
X954408D01*
G01X959008Y389166D02*
X954408D01*
G01X954214Y389162D02*
X949614D01*
G01X953597Y405256D02*
Y402056D01*
G01X959797Y405256D02*
X953597D01*
G01Y402056D02*
X959797D01*
G01X953597Y401001D02*
Y397801D01*
G01X959797Y401001D02*
X953597D01*
G01Y397801D02*
X959797D01*
G01X944969Y503478D02*
Y509678D01*
G01D02*
X941769D01*
G01Y503478D02*
X944969D01*
G01X941769Y509678D02*
Y503478D01*
G01X941570Y518588D02*
Y524788D01*
G01X944010Y970642D02*
Y964242D01*
G01X943261Y972162D02*
Y978162D01*
G01X955506Y1557676D02*
X961706D01*
Y1560876D01*
X955506D01*
Y1557676D01*
G01X955546Y1561656D02*
X961746D01*
Y1564856D01*
X955546D01*
Y1561656D01*
G01X940852Y1636953D02*
Y1633853D01*
X942308D01*
G01X941772Y1635351D02*
X940852D01*
G01X943875Y1636540D02*
X944182Y1636798D01*
X944527Y1636953D01*
X944833D01*
X945140Y1636798D01*
X945370Y1636540D01*
X945485Y1636178D01*
X945408Y1635816D01*
X945217Y1635506D01*
X944872Y1635300D01*
X944412Y1635196D01*
X944143Y1634990D01*
X944028Y1634628D01*
X944105Y1634266D01*
X944297Y1634008D01*
X944565Y1633853D01*
X944833D01*
X945102Y1633956D01*
X945332Y1634215D01*
G01X947780Y1636953D02*
Y1633853D01*
X947320Y1634473D01*
G01Y1636953D02*
X948240D01*
G01X992186Y1638620D02*
X941574D01*
G01D02*
Y1653120D01*
G01X947700Y1662200D02*
Y1668400D01*
G01X944500Y1662200D02*
X947700D01*
G01X944500Y1668400D02*
Y1662200D01*
G01X943700D02*
Y1668400D01*
G01X940500Y1662200D02*
X943700D01*
G01X940500Y1668400D02*
Y1662200D01*
G01X951700D02*
Y1668400D01*
G01X948500Y1662200D02*
X951700D01*
G01X948500Y1668400D02*
Y1662200D01*
G01X952300Y1668400D02*
Y1662200D01*
X955500D01*
Y1668400D01*
X952300D01*
G01X941574Y1653120D02*
X992186D01*
G01X947700Y1668400D02*
X944500D01*
G01X943700D02*
X940500D01*
G01X951700D02*
X948500D01*
G01X971580Y214299D02*
X965580D01*
G01X971580Y202299D02*
Y214299D01*
G01X965580Y202299D02*
X971580D01*
G01X965580Y214299D02*
Y202299D01*
G01X959008Y378966D02*
Y389166D01*
G01X959845Y379654D02*
X963045D01*
G01X959845Y385854D02*
Y379654D01*
G01X963045D02*
Y385854D01*
G01X968750Y379352D02*
X974950D01*
G01X968750Y382552D02*
Y379352D01*
G01X963045Y385854D02*
X959845D01*
G01X970956Y388702D02*
Y391902D01*
G01X964756Y388702D02*
X970956D01*
G01X964756Y391902D02*
Y388702D01*
G01X970956Y391902D02*
X964756D01*
G01X964689Y387789D02*
Y384589D01*
G01X970889Y387789D02*
X964689D01*
G01X970889Y384589D02*
Y387789D01*
G01X964689Y384589D02*
X970889D01*
G01X970956Y392578D02*
Y395778D01*
G01X964756Y392578D02*
X970956D01*
G01X964756Y395778D02*
Y392578D01*
G01X970956Y395778D02*
X964756D01*
G01X974950Y382552D02*
X968750D01*
G01X959797Y402056D02*
Y405256D01*
G01Y397801D02*
Y401001D01*
G01X964700Y403617D02*
Y400417D01*
G01X970900Y403617D02*
X964700D01*
G01X970900Y400417D02*
Y403617D01*
G01X964700Y400417D02*
X970900D01*
G01X964756Y399738D02*
Y396538D01*
G01X970956Y399738D02*
X964756D01*
G01X970956Y396538D02*
Y399738D01*
G01X964756Y396538D02*
X970956D01*
G01X965947Y508391D02*
X962747D01*
G01X965947Y502191D02*
Y508391D01*
G01X962747Y502191D02*
X965947D01*
G01X962747Y508391D02*
Y502191D01*
G01X969955Y508338D02*
X966755D01*
G01X969955Y502138D02*
Y508338D01*
G01X966755Y502138D02*
X969955D01*
G01X966755Y508338D02*
Y502138D01*
G01X970779Y502191D02*
X973979D01*
G01X970779Y508391D02*
Y502191D01*
G01X973979Y508391D02*
X970779D01*
G01X959020Y502162D02*
X962220D01*
G01X959020Y508362D02*
Y502162D01*
G01X962220Y508362D02*
X959020D01*
G01X962220Y502162D02*
Y508362D01*
G01X963970Y1563860D02*
Y1557660D01*
X967170D01*
Y1563860D01*
X963970D01*
G01X982030Y-13200D02*
Y-29800D01*
X991630D01*
Y-13200D01*
X982030D01*
G01Y16800D02*
Y200D01*
X991630D01*
Y16800D01*
X982030D01*
G01X987045Y180183D02*
X983845D01*
G01X987045Y173983D02*
Y180183D01*
G01X983845Y173983D02*
X987045D01*
G01X983845Y180183D02*
Y173983D01*
G01X985659Y340199D02*
X991859D01*
G01X985659Y343399D02*
Y340199D01*
G01X991859Y343399D02*
X985659D01*
G01X974950Y379352D02*
Y382552D01*
G01X988400Y398417D02*
Y393817D01*
G01D02*
X998600D01*
G01Y398417D02*
X988400D01*
G01X986619Y411296D02*
X989819D01*
G01X986619Y417496D02*
Y411296D01*
G01X985854D02*
Y417496D01*
G01X982654Y411296D02*
X985854D01*
G01X982654Y417496D02*
Y411296D01*
G01X978492D02*
X981692D01*
G01X978492Y417496D02*
Y411296D01*
G01X981692D02*
Y417496D01*
G01X989819D02*
X986619D01*
G01X985854D02*
X982654D01*
G01X985779Y420361D02*
X991979D01*
G01X985779Y423561D02*
Y420361D01*
G01X991979Y423561D02*
X985779D01*
G01X981692Y417496D02*
X978492D01*
G01X973979Y502191D02*
Y508391D01*
G01X1047736Y1420330D02*
G03I-31496J0D01*
G01X1002620Y-25617D02*
X1002310Y-25425D01*
X1002103Y-25195D01*
X1002000Y-24927D01*
X1002103Y-24620D01*
X1002310Y-24390D01*
X1002620Y-24160D01*
X1003033Y-24083D01*
X1005100D01*
G01X1002000Y-21750D02*
X1002052Y-21482D01*
X1002207Y-21175D01*
X1002465Y-20983D01*
X1002827Y-20907D01*
X1003188Y-20983D01*
X1003498Y-21213D01*
X1003653Y-21558D01*
Y-21942D01*
X1003757Y-22172D01*
X1004015Y-22363D01*
X1004377Y-22440D01*
X1004738Y-22325D01*
X1004997Y-22057D01*
X1005100Y-21750D01*
X1004997Y-21443D01*
X1004738Y-21175D01*
X1004377Y-21060D01*
X1004015Y-21137D01*
X1003757Y-21328D01*
X1003653Y-21558D01*
Y-21942D01*
X1003498Y-22287D01*
X1003188Y-22517D01*
X1002827Y-22593D01*
X1002465Y-22517D01*
X1002207Y-22325D01*
X1002052Y-22018D01*
X1002000Y-21750D01*
G01X1003292Y-19378D02*
X1003653Y-19110D01*
X1003860Y-18880D01*
X1003963Y-18573D01*
X1003860Y-18305D01*
X1003653Y-18113D01*
X1003343Y-17960D01*
X1002982Y-17922D01*
X1002672Y-17960D01*
X1002362Y-18113D01*
X1002103Y-18343D01*
X1002000Y-18612D01*
X1002103Y-18918D01*
X1002413Y-19187D01*
X1002878Y-19340D01*
X1003395Y-19378D01*
X1004067Y-19302D01*
X1004428Y-19187D01*
X1004790Y-18995D01*
X1005048Y-18727D01*
X1005100Y-18458D01*
X1004997Y-18190D01*
X1004738Y-17998D01*
G01X1002620Y4383D02*
X1002310Y4575D01*
X1002103Y4805D01*
X1002000Y5073D01*
X1002103Y5380D01*
X1002310Y5610D01*
X1002620Y5840D01*
X1003033Y5917D01*
X1005100D01*
G01X1003292Y7522D02*
X1003653Y7790D01*
X1003860Y8020D01*
X1003963Y8327D01*
X1003860Y8595D01*
X1003653Y8787D01*
X1003343Y8940D01*
X1002982Y8978D01*
X1002672Y8940D01*
X1002362Y8787D01*
X1002103Y8557D01*
X1002000Y8288D01*
X1002103Y7982D01*
X1002413Y7713D01*
X1002878Y7560D01*
X1003395Y7522D01*
X1004067Y7598D01*
X1004428Y7713D01*
X1004790Y7905D01*
X1005048Y8173D01*
X1005100Y8442D01*
X1004997Y8710D01*
X1004738Y8902D01*
G01X1002000Y11350D02*
X1002052Y11618D01*
X1002207Y11925D01*
X1002465Y12117D01*
X1002827Y12193D01*
X1003188Y12117D01*
X1003498Y11887D01*
X1003653Y11542D01*
Y11158D01*
X1003757Y10928D01*
X1004015Y10737D01*
X1004377Y10660D01*
X1004738Y10775D01*
X1004997Y11043D01*
X1005100Y11350D01*
X1004997Y11657D01*
X1004738Y11925D01*
X1004377Y12040D01*
X1004015Y11963D01*
X1003757Y11772D01*
X1003653Y11542D01*
Y11158D01*
X1003498Y10813D01*
X1003188Y10583D01*
X1002827Y10507D01*
X1002465Y10583D01*
X1002207Y10775D01*
X1002052Y11082D01*
X1002000Y11350D01*
G01X1004159Y340229D02*
Y343429D01*
G01X997959Y340229D02*
X1004159D01*
G01X997959Y343429D02*
Y340229D01*
G01X1004159Y343429D02*
X997959D01*
G01X991859Y340199D02*
Y343399D01*
G01X998900Y382462D02*
Y379262D01*
G01X1005100D02*
Y382462D01*
G01X998900Y379262D02*
X1005100D01*
G01X993500Y393817D02*
Y398417D01*
G01X998600Y393817D02*
Y398417D01*
G01X989900Y388962D02*
Y385762D01*
G01X996100Y388962D02*
X989900D01*
G01X996100Y385762D02*
Y388962D01*
G01X989900Y385762D02*
X996100D01*
G01X989900Y384962D02*
Y381762D01*
G01X996100Y384962D02*
X989900D01*
G01X996100Y381762D02*
Y384962D01*
G01X989900Y381762D02*
X996100D01*
G01X989900Y392962D02*
Y389762D01*
G01X996100Y392962D02*
X989900D01*
G01X996100Y389762D02*
Y392962D01*
G01X989900Y389762D02*
X996100D01*
G01X1005100Y382462D02*
X998900D01*
G01X990745Y411296D02*
X993945D01*
G01X990745Y417496D02*
Y411296D01*
G01X993945D02*
Y417496D01*
G01X1005789Y405798D02*
X1002589D01*
G01Y399598D02*
X1005789D01*
G01X1002589Y405798D02*
Y399598D01*
G01X989981Y402207D02*
Y399007D01*
G01X996181Y402207D02*
X989981D01*
G01X996181Y399007D02*
Y402207D01*
G01X989981Y399007D02*
X996181D01*
G01X989819Y411296D02*
Y417496D01*
G01X993945D02*
X990745D01*
G01X991979Y420361D02*
Y423561D01*
G01X1000146Y424282D02*
Y421082D01*
G01X1006346Y424282D02*
X1000146D01*
G01Y421082D02*
X1006346D01*
G01X1000146Y417562D02*
X1006346D01*
G01X1000146Y420762D02*
Y417562D01*
G01X1006346Y420762D02*
X1000146D01*
G01X993356Y422802D02*
X996556D01*
G01X993356Y429002D02*
Y422802D01*
G01X996556Y429002D02*
X993356D01*
G01X996556Y422802D02*
Y429002D01*
G01X1005135Y1259410D02*
Y1256210D01*
G01D02*
X1011335D01*
G01X1005135Y1255469D02*
Y1252269D01*
G01X1011335Y1255469D02*
X1005135D01*
G01Y1252269D02*
X1011335D01*
G01Y1259410D02*
X1005135D01*
G01X1022606Y1631392D02*
Y1668532D01*
X998118D01*
Y1631492D01*
G01Y1631249D02*
X1022606D01*
G01X998118Y1631643D02*
X1022606D01*
G01X998118Y1631682D02*
X1022606D01*
G01X998118Y1633699D02*
Y1631292D01*
G01Y1631643D02*
X1022606D01*
G01X998118D02*
X1022606D01*
G01X998118Y1632405D02*
Y1633605D01*
G01X1022606Y1631492D02*
Y1628868D01*
X998118D01*
Y1631337D01*
G01Y1632018D02*
Y1633305D01*
G01Y1630749D02*
X1022606D01*
G01X998118Y1630449D02*
X1022606D01*
G01X998118Y1630049D02*
X1022606D01*
G01X998118Y1629649D02*
X1022606D01*
G01X998118Y1629449D02*
X1022606D01*
G01X998118Y1629249D02*
X1022606D01*
G01X992186Y1653120D02*
Y1638620D01*
G01X996595Y1668385D02*
X993495D01*
Y1667465D01*
X993650Y1667158D01*
X994012Y1666928D01*
X994425Y1666851D01*
X994838Y1666928D01*
X995148Y1667120D01*
X995303Y1667465D01*
Y1668385D01*
G01X996595Y1665361D02*
X993495D01*
Y1664595D01*
X993650Y1664288D01*
X993857Y1664058D01*
X994167Y1663866D01*
X994528Y1663713D01*
X995045Y1663675D01*
X995562Y1663713D01*
X995923Y1663866D01*
X996233Y1664058D01*
X996440Y1664288D01*
X996595Y1664595D01*
Y1665361D01*
G01Y1661418D02*
X993495D01*
X994115Y1661878D01*
G01X996595D02*
Y1660958D01*
G01X996130Y1659161D02*
X996388Y1658931D01*
X996543Y1658663D01*
X996595Y1658318D01*
X996492Y1657973D01*
X996285Y1657705D01*
X995923Y1657513D01*
X995510Y1657475D01*
X995097Y1657551D01*
X994838Y1657743D01*
X994632Y1658011D01*
X994580Y1658280D01*
X994632Y1658548D01*
X994838Y1658893D01*
X993495Y1658778D01*
Y1657743D01*
G01X1008620Y-37617D02*
X1008310Y-37425D01*
X1008103Y-37195D01*
X1008000Y-36927D01*
X1008103Y-36620D01*
X1008310Y-36390D01*
X1008620Y-36160D01*
X1009033Y-36083D01*
X1011100D01*
G01X1008000Y-33750D02*
X1011100D01*
X1010480Y-34210D01*
G01X1008000D02*
Y-33290D01*
G01Y-30650D02*
X1011100D01*
X1010480Y-31110D01*
G01X1008000D02*
Y-30190D01*
G01Y-27550D02*
X1008052Y-27282D01*
X1008207Y-26975D01*
X1008465Y-26783D01*
X1008827Y-26707D01*
X1009188Y-26783D01*
X1009498Y-27013D01*
X1009653Y-27358D01*
Y-27742D01*
X1009757Y-27972D01*
X1010015Y-28163D01*
X1010377Y-28240D01*
X1010738Y-28125D01*
X1010997Y-27857D01*
X1011100Y-27550D01*
X1010997Y-27243D01*
X1010738Y-26975D01*
X1010377Y-26860D01*
X1010015Y-26937D01*
X1009757Y-27128D01*
X1009653Y-27358D01*
Y-27742D01*
X1009498Y-28087D01*
X1009188Y-28317D01*
X1008827Y-28393D01*
X1008465Y-28317D01*
X1008207Y-28125D01*
X1008052Y-27818D01*
X1008000Y-27550D01*
G01X1009120Y-16617D02*
X1008810Y-16425D01*
X1008603Y-16195D01*
X1008500Y-15927D01*
X1008603Y-15620D01*
X1008810Y-15390D01*
X1009120Y-15160D01*
X1009533Y-15083D01*
X1011600D01*
G01X1008500Y-12750D02*
X1011600D01*
X1010980Y-13210D01*
G01X1008500D02*
Y-12290D01*
G01X1011083Y-10378D02*
X1011393Y-10148D01*
X1011548Y-9880D01*
X1011600Y-9573D01*
X1011497Y-9190D01*
X1011238Y-8922D01*
X1010928Y-8845D01*
X1010618Y-8883D01*
X1010360Y-9037D01*
X1009843Y-9803D01*
X1009482Y-10148D01*
X1008965Y-10378D01*
X1008500Y-10455D01*
Y-8845D01*
G01Y-6550D02*
X1011600D01*
X1010980Y-7010D01*
G01X1008500D02*
Y-6090D01*
G01X1009120Y4383D02*
X1008810Y4575D01*
X1008603Y4805D01*
X1008500Y5073D01*
X1008603Y5380D01*
X1008810Y5610D01*
X1009120Y5840D01*
X1009533Y5917D01*
X1011600D01*
G01X1008500Y8173D02*
X1009172Y8250D01*
X1009740Y8365D01*
X1010257Y8518D01*
X1010825Y8710D01*
X1011600Y9017D01*
Y7483D01*
G01X1009792Y10622D02*
X1010153Y10890D01*
X1010360Y11120D01*
X1010463Y11427D01*
X1010360Y11695D01*
X1010153Y11887D01*
X1009843Y12040D01*
X1009482Y12078D01*
X1009172Y12040D01*
X1008862Y11887D01*
X1008603Y11657D01*
X1008500Y11388D01*
X1008603Y11082D01*
X1008913Y10813D01*
X1009378Y10660D01*
X1009895Y10622D01*
X1010567Y10698D01*
X1010928Y10813D01*
X1011290Y11005D01*
X1011548Y11273D01*
X1011600Y11542D01*
X1011497Y11810D01*
X1011238Y12002D01*
G01X1018060Y193009D02*
X1024260D01*
G01Y196209D02*
X1018060D01*
G01D02*
Y193009D01*
G01X1011230D02*
X1017430D01*
G01D02*
Y196209D01*
G01D02*
X1011230D01*
G01D02*
Y193009D01*
G01X1010105Y219853D02*
Y216653D01*
G01D02*
X1016305D01*
G01D02*
Y219853D01*
G01X1006955Y216653D02*
X1013155D01*
G01D02*
Y219853D01*
G01X1006955D02*
Y216653D01*
G01X1016305Y219853D02*
X1010105D01*
G01X1013155D02*
X1006955D01*
G01X1011342Y299670D02*
Y293470D01*
G01D02*
X1014542D01*
G01D02*
Y299670D01*
G01X1007342D02*
Y293470D01*
G01D02*
X1010542D01*
G01D02*
Y299670D01*
G01X1018469Y304513D02*
Y298313D01*
G01D02*
X1021669D01*
G01X1014542Y299670D02*
X1011342D01*
G01X1010542D02*
X1007342D01*
G01X1021669Y304513D02*
X1018469D01*
G01X1019320Y312462D02*
X1016120D01*
G01X1019320Y306262D02*
Y312462D01*
G01X1016120Y306262D02*
X1019320D01*
G01X1016120Y312462D02*
Y306262D01*
G01X1015320Y312462D02*
X1012120D01*
G01X1015320Y306262D02*
Y312462D01*
G01X1012120Y306262D02*
X1015320D01*
G01X1012120Y312462D02*
Y306262D01*
G01X1007400Y378762D02*
X1010600D01*
G01X1007400Y384962D02*
Y378762D01*
G01X1010600D02*
Y384962D01*
G01X1016400Y379262D02*
X1022600D01*
G01X1016400Y382462D02*
Y379262D01*
G01X1010600Y384962D02*
X1007400D01*
G01X1016400Y384262D02*
X1022600D01*
G01X1016400Y387462D02*
Y384262D01*
G01X1022600Y387462D02*
X1016400D01*
G01X1022600Y382462D02*
X1016400D01*
G01Y392762D02*
X1022600D01*
G01X1016400Y395962D02*
Y392762D01*
G01X1022600Y395962D02*
X1016400D01*
G01X1005789Y399598D02*
Y405798D01*
G01X1016400Y396762D02*
X1022600D01*
G01X1016400Y399962D02*
Y396762D01*
G01X1022600Y399962D02*
X1016400D01*
G01X1010934Y405767D02*
X1007734D01*
G01X1010934Y399567D02*
Y405767D01*
G01X1007734Y399567D02*
X1010934D01*
G01X1007734Y405767D02*
Y399567D01*
G01X1014705Y405810D02*
X1011505D01*
G01X1014705Y399610D02*
Y405810D01*
G01X1011505Y399610D02*
X1014705D01*
G01X1011505Y405810D02*
Y399610D01*
G01X1006346Y421082D02*
Y424282D01*
G01Y417562D02*
Y420762D01*
G01X1014163Y422148D02*
Y418948D01*
G01X1020363Y422148D02*
X1014163D01*
G01X1020363Y418948D02*
Y422148D01*
G01X1014163Y418948D02*
X1020363D01*
G01Y415374D02*
Y418574D01*
G01X1014163Y415374D02*
X1020363D01*
G01X1014163Y418574D02*
Y415374D01*
G01X1020363Y418574D02*
X1014163D01*
G01X1011335Y1256210D02*
Y1259410D01*
G01X1018505Y1252663D02*
Y1255863D01*
G01X1012305Y1252663D02*
X1018505D01*
G01X1012305Y1255863D02*
Y1252663D01*
G01X1018505Y1255863D02*
X1012305D01*
G01X1021141Y1258544D02*
Y1255344D01*
G01X1027341Y1258544D02*
X1021141D01*
G01Y1255344D02*
X1027341D01*
G01X1011335Y1252269D02*
Y1255469D01*
G01X1021241Y1259944D02*
X1027241D01*
G01X1021241Y1271944D02*
Y1259944D01*
G01X1027241Y1271944D02*
X1021241D01*
G01X1018841Y1259844D02*
Y1271844D01*
G01X1012841Y1259844D02*
X1018841D01*
G01X1012841Y1271844D02*
Y1259844D01*
G01X1018841Y1271844D02*
X1012841D01*
G01X1011062Y1625599D02*
Y1628025D01*
G01X1010362Y1647168D02*
Y1645368D01*
G01X1015362Y1647168D02*
X1005362D01*
G01X1014362Y1652168D02*
X1006362D01*
X1010362Y1647168D01*
X1014362Y1652168D01*
G01X1010362Y1654368D02*
Y1652568D01*
G01X1010462Y1670041D02*
Y1672281D01*
G01X1012087Y1671068D02*
X1008837D01*
G01X1031302Y-39811D02*
Y-23211D01*
X1021702D01*
Y-39811D01*
X1031302D01*
G01Y-19811D02*
Y-3211D01*
X1021702D01*
Y-19811D01*
X1031302D01*
G01Y189D02*
Y16789D01*
X1021702D01*
Y189D01*
X1031302D01*
G01X1037728Y142177D02*
X1037498Y141815D01*
X1037192Y141609D01*
X1036847Y141557D01*
X1036540Y141609D01*
X1036233Y141867D01*
X1036042Y142177D01*
X1036003Y142487D01*
X1036080Y142849D01*
X1036348Y143107D01*
X1036617Y143210D01*
X1036962D01*
G01X1036617D02*
X1036387Y143365D01*
X1036195Y143624D01*
X1036118Y143934D01*
X1036195Y144244D01*
X1036387Y144502D01*
X1036732Y144657D01*
X1037077Y144605D01*
X1037422Y144399D01*
G01X1036935Y161857D02*
Y164957D01*
X1037395Y164337D01*
G01Y161857D02*
X1036475D01*
G01X1089154Y204724D02*
G03I-31496J0D01*
G01X1024260Y193009D02*
Y196209D01*
G01X1039833Y241162D02*
X1037407D01*
G01X1025699Y298313D02*
Y304513D01*
G01X1022499D02*
Y298313D01*
G01D02*
X1025699D01*
G01X1021669D02*
Y304513D01*
G01X1035400Y298112D02*
Y291912D01*
G01D02*
X1038600D01*
G01Y298112D02*
X1035400D01*
G01X1025699Y304513D02*
X1022499D01*
G01X1022600Y379262D02*
Y382462D01*
G01X1030141Y395005D02*
Y399605D01*
G01X1025041D02*
Y395005D01*
G01X1035241D02*
Y399605D01*
G01X1025041Y395005D02*
X1035241D01*
G01X1022600Y384262D02*
Y387462D01*
G01Y392762D02*
Y395962D01*
G01X1034088Y388437D02*
X1037288D01*
G01X1034088Y394637D02*
Y388437D01*
G01X1037288Y394637D02*
X1034088D01*
G01X1037288Y388437D02*
Y394637D01*
G01X1035241Y399605D02*
X1025041D01*
G01X1023939Y415028D02*
Y410428D01*
G01X1034139D02*
Y415028D01*
G01X1023939Y410428D02*
X1034139D01*
G01X1036732Y409113D02*
X1023852D01*
G01Y402713D02*
X1036732D01*
G01X1023852Y409113D02*
Y402713D01*
G01X1036732Y409113D02*
Y402713D01*
G01X1022600Y396762D02*
Y399962D01*
G01X1034200Y421417D02*
X1029600D01*
G01Y416317D02*
X1034200D01*
G01X1029600Y426517D02*
Y416317D01*
G01X1034200Y426517D02*
X1029600D01*
G01X1034200Y416317D02*
Y426517D01*
G01X1034139Y415028D02*
X1023939D01*
G01X1034841Y1258544D02*
Y1255344D01*
G01X1041041Y1258544D02*
X1034841D01*
G01Y1255344D02*
X1041041D01*
G01X1027341D02*
Y1258544D01*
G01X1027355Y1253103D02*
Y1249903D01*
G01X1033555Y1253103D02*
X1027355D01*
G01X1033555Y1249903D02*
Y1253103D01*
G01X1027355Y1249903D02*
X1033555D01*
G01X1027241Y1259944D02*
Y1271944D01*
G01X1034941Y1259944D02*
X1040941D01*
G01X1034941Y1271944D02*
Y1259944D01*
G01X1040941Y1271944D02*
X1034941D01*
G01X1022313Y1631605D02*
X1022113Y1631618D01*
G01X1022606Y1631492D02*
Y1632018D01*
G01Y1631292D02*
Y1636172D01*
G01X1037150Y1625683D02*
Y1628109D01*
G01X1048694Y1631476D02*
Y1668616D01*
X1024206D01*
Y1631576D01*
G01Y1631333D02*
X1048694D01*
G01X1024206Y1631727D02*
X1048694D01*
G01X1024206Y1631766D02*
X1048694D01*
G01X1024206Y1633783D02*
Y1631376D01*
G01Y1631727D02*
X1048694D01*
G01X1024206D02*
X1048694D01*
G01X1024206Y1632489D02*
Y1633689D01*
G01X1048694Y1631576D02*
Y1628952D01*
X1024206D01*
Y1631421D01*
G01Y1632102D02*
Y1633389D01*
G01Y1630833D02*
X1048694D01*
G01X1024206Y1630533D02*
X1048694D01*
G01X1024206Y1630133D02*
X1048694D01*
G01X1024206Y1629733D02*
X1048694D01*
G01X1024206Y1629533D02*
X1048694D01*
G01X1024206Y1629333D02*
X1048694D01*
G01X1022606Y1633805D02*
Y1633699D01*
G01X1036450Y1647252D02*
Y1645452D01*
G01X1041450Y1647252D02*
X1031450D01*
G01X1040450Y1652252D02*
X1032450D01*
X1036450Y1647252D01*
X1040450Y1652252D01*
G01X1036450Y1654452D02*
Y1652652D01*
G01X1036550Y1670125D02*
Y1672365D01*
G01X1038175Y1671152D02*
X1034925D01*
G01X1052518Y141951D02*
X1052288Y141589D01*
X1051982Y141383D01*
X1051637Y141331D01*
X1051330Y141383D01*
X1051023Y141641D01*
X1050832Y141951D01*
X1050793Y142261D01*
X1050870Y142623D01*
X1051138Y142881D01*
X1051407Y142984D01*
X1051752D01*
G01X1051407D02*
X1051177Y143139D01*
X1050985Y143398D01*
X1050908Y143708D01*
X1050985Y144018D01*
X1051177Y144276D01*
X1051522Y144431D01*
X1051867Y144379D01*
X1052212Y144173D01*
G01X1051725Y161631D02*
Y164731D01*
X1052185Y164111D01*
G01Y161631D02*
X1051265D01*
G01X1041891Y245206D02*
X1077631D01*
G01X1041891Y262136D02*
Y245206D01*
G01X1077631Y262136D02*
X1041891D01*
G01X1038600Y291912D02*
Y298112D01*
G01X1038300Y379422D02*
X1044700D01*
G01D02*
Y392302D01*
G01X1038300D02*
Y379422D01*
G01Y392302D02*
X1044700D01*
G01X1045900Y382762D02*
X1049100D01*
G01X1045900Y388962D02*
Y382762D01*
G01X1049100Y388962D02*
X1045900D01*
G01X1049100Y382762D02*
Y388962D01*
G01X1052149Y758724D02*
X1055349D01*
G01X1052149Y764924D02*
Y758724D01*
G01X1055349Y764924D02*
X1052149D01*
G01X1041041Y1255344D02*
Y1258544D01*
G01X1050904Y1252561D02*
X1054104D01*
G01X1050904Y1258761D02*
Y1252561D01*
G01X1048007Y1253113D02*
Y1256313D01*
G01X1041807Y1253113D02*
X1048007D01*
G01X1041807Y1256313D02*
Y1253113D01*
G01X1048007Y1256313D02*
X1041807D01*
G01X1040941Y1259944D02*
Y1271944D01*
G01X1050941Y1259944D02*
X1056941D01*
G01X1050941Y1271944D02*
Y1259944D01*
G01X1056941Y1271944D02*
X1050941D01*
G01X1054104Y1258761D02*
X1050904D01*
G01X1048401Y1631689D02*
X1048201Y1631702D01*
G01X1048694Y1631576D02*
Y1632102D01*
G01Y1631376D02*
Y1636256D01*
G01Y1633889D02*
Y1633783D01*
G01X1054633Y1667979D02*
X1051533D01*
Y1667059D01*
X1051688Y1666752D01*
X1052050Y1666522D01*
X1052463Y1666445D01*
X1052876Y1666522D01*
X1053186Y1666714D01*
X1053341Y1667059D01*
Y1667979D01*
G01X1054633Y1664955D02*
X1051533D01*
Y1664189D01*
X1051688Y1663882D01*
X1051895Y1663652D01*
X1052205Y1663460D01*
X1052566Y1663307D01*
X1053083Y1663269D01*
X1053600Y1663307D01*
X1053961Y1663460D01*
X1054271Y1663652D01*
X1054478Y1663882D01*
X1054633Y1664189D01*
Y1664955D01*
G01Y1661012D02*
X1051533D01*
X1052153Y1661472D01*
G01X1054633D02*
Y1660552D01*
G01X1053341Y1658640D02*
X1052980Y1658372D01*
X1052773Y1658142D01*
X1052670Y1657835D01*
X1052773Y1657567D01*
X1052980Y1657375D01*
X1053290Y1657222D01*
X1053651Y1657184D01*
X1053961Y1657222D01*
X1054271Y1657375D01*
X1054530Y1657605D01*
X1054633Y1657874D01*
X1054530Y1658180D01*
X1054220Y1658449D01*
X1053755Y1658602D01*
X1053238Y1658640D01*
X1052566Y1658564D01*
X1052205Y1658449D01*
X1051843Y1658257D01*
X1051585Y1657989D01*
X1051533Y1657720D01*
X1051636Y1657452D01*
X1051895Y1657260D01*
G01X1078618Y272600D02*
X1066618D01*
G01Y266600D02*
X1078618D01*
G01X1066618Y272600D02*
Y266600D01*
G01X1066299Y277874D02*
X1078299D01*
G01X1066299Y283874D02*
Y277874D01*
G01X1078299Y283874D02*
X1066299D01*
G01X1056149Y758724D02*
X1059349D01*
G01X1056149Y764924D02*
Y758724D01*
G01X1059349Y764924D02*
X1056149D01*
G01X1059349Y758724D02*
Y764924D01*
G01X1064149Y758724D02*
X1067349D01*
G01X1064149Y764924D02*
Y758724D01*
G01X1067349Y764924D02*
X1064149D01*
G01X1067349Y758724D02*
Y764924D01*
G01X1060149Y758724D02*
X1063349D01*
G01X1060149Y764924D02*
Y758724D01*
G01X1063349Y764924D02*
X1060149D01*
G01X1063349Y758724D02*
Y764924D01*
G01X1055349Y758724D02*
Y764924D01*
G01X1064541Y1258544D02*
Y1255344D01*
G01X1070741Y1258544D02*
X1064541D01*
G01Y1255344D02*
X1070741D01*
G01X1054104Y1252561D02*
Y1258761D01*
G01X1064541Y1252877D02*
Y1249677D01*
G01X1070741Y1252877D02*
X1064541D01*
G01Y1249677D02*
X1070741D01*
G01X1064641Y1259944D02*
X1070641D01*
G01X1064641Y1271944D02*
Y1259944D01*
G01X1070641Y1271944D02*
X1064641D01*
G01X1056941Y1259944D02*
Y1271944D01*
G01X1082456Y254123D02*
X1080216D01*
G01X1081429Y255748D02*
Y252498D01*
G01X1077631Y262138D02*
X1077634Y245198D01*
G01X1078231Y262138D02*
X1078235Y245163D01*
G01X1078831Y262138D02*
X1078825Y245155D01*
G01X1078781Y245205D02*
X1077272Y245209D01*
G01X1077631Y245206D02*
Y262136D01*
G01X1078831Y262138D02*
X1077631D01*
G01X1078618Y266600D02*
Y272600D01*
G01X1078299Y277874D02*
Y283874D01*
G01X1116974Y605380D02*
G03I-22900J0D01*
G01X1085596Y759379D02*
X1088796D01*
G01X1085596Y765579D02*
Y759379D01*
G01X1088796Y765579D02*
X1085596D01*
G01X1081696Y759379D02*
X1084896D01*
G01X1081696Y765579D02*
Y759379D01*
G01X1084896Y765579D02*
X1081696D01*
G01X1084896Y759379D02*
Y765579D01*
G01X1070741Y1255344D02*
Y1258544D01*
G01X1077704Y1252904D02*
Y1256104D01*
G01X1071504Y1252904D02*
X1077704D01*
G01X1071504Y1256104D02*
Y1252904D01*
G01X1077704Y1256104D02*
X1071504D01*
G01X1083630Y1252752D02*
Y1258952D01*
G01X1080430Y1252752D02*
X1083630D01*
G01X1080430Y1258952D02*
Y1252752D01*
G01X1070741Y1249677D02*
Y1252877D01*
G01X1080641Y1259944D02*
X1086641D01*
G01X1080641Y1271944D02*
Y1259944D01*
G01X1086641Y1271944D02*
X1080641D01*
G01X1070641Y1259944D02*
Y1271944D01*
G01X1083630Y1258952D02*
X1080430D01*
G01X1089496Y759379D02*
X1092696D01*
G01X1089496Y765579D02*
Y759379D01*
G01X1092696Y765579D02*
X1089496D01*
G01X1092696Y759379D02*
Y765579D01*
G01X1097296Y759379D02*
X1100496D01*
G01X1097296Y765579D02*
Y759379D01*
G01X1100496Y765579D02*
X1097296D01*
G01X1100496Y759379D02*
Y765579D01*
G01X1101196Y759379D02*
X1104396D01*
G01X1101196Y765579D02*
Y759379D01*
G01X1104396Y765579D02*
X1101196D01*
G01X1093396Y759379D02*
X1096596D01*
G01X1093396Y765579D02*
Y759379D01*
G01X1096596Y765579D02*
X1093396D01*
G01X1096596Y759379D02*
Y765579D01*
G01X1088796Y759379D02*
Y765579D01*
G01X1094241Y1258544D02*
Y1255344D01*
G01X1100441Y1258544D02*
X1094241D01*
G01X1100441Y1255344D02*
Y1258544D01*
G01X1094241Y1255344D02*
X1100441D01*
G01X1090872Y1253009D02*
Y1249809D01*
G01X1097072Y1253009D02*
X1090872D01*
G01X1097072Y1249809D02*
Y1253009D01*
G01X1090872Y1249809D02*
X1097072D01*
G01X1086641Y1259944D02*
Y1271944D01*
G01X1100341Y1259944D02*
Y1271944D01*
G01X1094341Y1259944D02*
X1100341D01*
G01X1094341Y1271944D02*
Y1259944D01*
G01X1100341Y1271944D02*
X1094341D01*
G01X1096263Y1701390D02*
X1096033Y1701028D01*
X1095727Y1700822D01*
X1095382Y1700770D01*
X1095075Y1700822D01*
X1094768Y1701080D01*
X1094577Y1701390D01*
X1094538Y1701700D01*
X1094615Y1702062D01*
X1094883Y1702320D01*
X1095152Y1702423D01*
X1095497D01*
G01X1095152D02*
X1094922Y1702578D01*
X1094730Y1702837D01*
X1094653Y1703147D01*
X1094730Y1703457D01*
X1094922Y1703715D01*
X1095267Y1703870D01*
X1095612Y1703818D01*
X1095957Y1703612D01*
G01X1095470Y1721070D02*
Y1724170D01*
X1095930Y1723550D01*
G01Y1721070D02*
X1095010D01*
G01X1114269Y759464D02*
X1117469D01*
G01X1114269Y765664D02*
Y759464D01*
G01X1117469Y765664D02*
X1114269D01*
G01X1117469Y759464D02*
Y765664D01*
G01X1105096Y759379D02*
X1108296D01*
G01X1105096Y765579D02*
Y759379D01*
G01X1108296Y765579D02*
X1105096D01*
G01X1108296Y759379D02*
Y765579D01*
G01X1104396Y759379D02*
Y765579D01*
G01X1118269Y759464D02*
X1121469D01*
G01X1118269Y765664D02*
Y759464D01*
G01X1121469Y765664D02*
X1118269D01*
G01X1109080Y759541D02*
X1112280D01*
G01X1109080Y765741D02*
Y759541D01*
G01X1112280Y765741D02*
X1109080D01*
G01X1112280Y759541D02*
Y765741D01*
G01X1113553Y1233642D02*
Y1236742D01*
X1112787D01*
X1112480Y1236587D01*
X1112250Y1236380D01*
X1112058Y1236070D01*
X1111905Y1235709D01*
X1111867Y1235192D01*
X1111905Y1234675D01*
X1112058Y1234314D01*
X1112250Y1234004D01*
X1112480Y1233797D01*
X1112787Y1233642D01*
X1113553D01*
G01X1109150D02*
Y1236742D01*
X1110568Y1234520D01*
X1108652D01*
G01X1107353Y1234262D02*
X1107123Y1233900D01*
X1106817Y1233694D01*
X1106472Y1233642D01*
X1106165Y1233694D01*
X1105858Y1233952D01*
X1105667Y1234262D01*
X1105628Y1234572D01*
X1105705Y1234934D01*
X1105973Y1235192D01*
X1106242Y1235295D01*
X1106587D01*
G01X1106242D02*
X1106012Y1235450D01*
X1105820Y1235709D01*
X1105743Y1236019D01*
X1105820Y1236329D01*
X1106012Y1236587D01*
X1106357Y1236742D01*
X1106702Y1236690D01*
X1107047Y1236484D01*
G01X1115307Y1255049D02*
Y1251849D01*
G01X1121507Y1255049D02*
X1115307D01*
G01Y1251849D02*
X1121507D01*
G01X1115307Y1255849D02*
X1121507D01*
G01X1115307Y1259049D02*
Y1255849D01*
G01X1104117Y1253281D02*
X1107317D01*
G01X1104117Y1259481D02*
Y1253281D01*
G01X1107317D02*
Y1259481D01*
G01X1113504Y1252595D02*
Y1258795D01*
G01X1110304Y1252595D02*
X1113504D01*
G01X1110304Y1258795D02*
Y1252595D01*
G01X1116341Y1259944D02*
Y1271944D01*
G01X1110341Y1259944D02*
X1116341D01*
G01X1110341Y1271944D02*
Y1259944D01*
G01X1116341Y1271944D02*
X1110341D01*
G01X1121507Y1259049D02*
X1115307D01*
G01X1107317Y1259481D02*
X1104117D01*
G01X1113504Y1258795D02*
X1110304D01*
G01X1119020Y1390713D02*
Y1396913D01*
X1115820D01*
Y1390713D01*
X1119020D01*
G01X1126269Y759464D02*
X1129469D01*
G01X1126269Y765664D02*
Y759464D01*
G01X1129469Y765664D02*
X1126269D01*
G01X1129469Y759464D02*
Y765664D01*
G01X1121469Y759464D02*
Y765664D01*
G01X1122269Y759464D02*
X1125469D01*
G01X1122269Y765664D02*
Y759464D01*
G01X1125469Y765664D02*
X1122269D01*
G01X1125469Y759464D02*
Y765664D01*
G01X1125842Y1230571D02*
X1128082D01*
G01X1126869Y1228946D02*
Y1232196D01*
G01X1134970Y1245705D02*
Y1243279D01*
G01X1127069Y1242758D02*
X1129038Y1240790D01*
G01X1125100D02*
X1127069Y1242758D01*
G01X1129038Y1240790D02*
X1125100D01*
G01X1124313Y1233921D02*
X1129825D01*
G01X1124313Y1250069D02*
Y1233921D01*
G01X1129825D02*
Y1250069D01*
G01X1136939Y1238796D02*
X1133739D01*
G01Y1232596D02*
X1136939D01*
G01X1133739Y1238796D02*
Y1232596D01*
G01X1129038Y1243152D02*
X1125100D01*
G01X1124319Y1251221D02*
Y1250721D01*
G01X1129819Y1251221D02*
X1124319D01*
G01X1129819Y1250471D02*
Y1251221D01*
G01X1124569Y1250471D02*
X1129819D01*
G01X1124569Y1250071D02*
Y1250471D01*
G01X1124319Y1250071D02*
X1124569D01*
G01X1124319Y1250771D02*
Y1250071D01*
G01X1129819Y1250771D02*
X1124319D01*
G01X1129819Y1250121D02*
Y1250771D01*
G01X1129719Y1250121D02*
X1129819D01*
G01X1129825Y1250069D02*
X1124313D01*
G01X1123941Y1258544D02*
Y1255344D01*
G01X1130141Y1258544D02*
X1123941D01*
G01X1130141Y1255344D02*
Y1258544D01*
G01X1123941Y1255344D02*
X1130141D01*
G01X1131448Y1258262D02*
X1137648D01*
G01X1131448Y1261462D02*
Y1258262D01*
G01X1121507Y1251849D02*
Y1255049D01*
G01Y1255849D02*
Y1259049D01*
G01X1130361Y1253083D02*
Y1249883D01*
G01X1136561Y1253083D02*
X1130361D01*
G01Y1249883D02*
X1136561D01*
G01X1130041Y1259944D02*
Y1271944D01*
G01X1124041Y1259944D02*
X1130041D01*
G01X1124041Y1271944D02*
Y1259944D01*
G01X1130041Y1271944D02*
X1124041D01*
G01X1137648Y1261462D02*
X1131448D01*
G01X1125980Y1400344D02*
X1119980D01*
Y1388344D01*
X1125980D01*
Y1400344D01*
G01X1135476Y1377702D02*
X1137716D01*
G01X1136503Y1376077D02*
Y1379327D01*
G01X1145657Y1383870D02*
Y1419566D01*
X1127941D01*
Y1383870D01*
X1145657D01*
G01X1136499Y1422405D02*
Y1424831D01*
G01X1120153Y1436479D02*
X1123353D01*
G01X1120153Y1442679D02*
Y1436479D01*
G01X1123353D02*
Y1442679D01*
G01X1125500Y1429155D02*
X1128700D01*
G01X1125500Y1435355D02*
Y1429155D01*
G01X1128700Y1435355D02*
X1125500D01*
G01X1128700Y1429155D02*
Y1435355D01*
G01X1123353Y1442679D02*
X1120153D01*
G01X1124500Y1443182D02*
X1127700D01*
G01X1124500Y1449382D02*
Y1443182D01*
G01X1127700Y1449382D02*
X1124500D01*
G01X1127700Y1443182D02*
Y1449382D01*
G01X1134087Y1589838D02*
Y1583638D01*
X1137287D01*
Y1589838D01*
X1134087D01*
G01X1130087D02*
Y1583638D01*
X1133287D01*
Y1589838D01*
X1130087D01*
G01X1147867Y587422D02*
X1151067D01*
G01X1147867Y593622D02*
Y587422D01*
G01X1151067D02*
Y593622D01*
G01X1143867Y587422D02*
X1147067D01*
G01X1143867Y593622D02*
Y587422D01*
G01X1147067D02*
Y593622D01*
G01X1151077Y604482D02*
Y607682D01*
G01X1144877Y604482D02*
X1151077D01*
G01X1144877Y607682D02*
Y604482D01*
G01X1151077Y607682D02*
X1144877D01*
G01X1151087Y597522D02*
Y600722D01*
G01X1144887Y597522D02*
X1151087D01*
G01X1144887Y600722D02*
Y597522D01*
G01X1151087Y600722D02*
X1144887D01*
G01X1151067Y593622D02*
X1147867D01*
G01X1147067D02*
X1143867D01*
G01X1136939Y1232596D02*
Y1238796D01*
G01X1137648Y1258262D02*
Y1261462D01*
G01X1141321Y1253077D02*
X1144521D01*
G01X1141321Y1259277D02*
Y1253077D01*
G01X1144521D02*
Y1259277D01*
G01X1151503Y1251934D02*
X1148303D01*
G01X1151503Y1245734D02*
Y1251934D01*
G01X1148303Y1245734D02*
X1151503D01*
G01X1148303Y1251934D02*
Y1245734D01*
G01X1136561Y1249883D02*
Y1253083D01*
G01X1146041Y1259944D02*
Y1271944D01*
G01X1140041Y1259944D02*
X1146041D01*
G01X1140041Y1271944D02*
Y1259944D01*
G01X1146041Y1271944D02*
X1140041D01*
G01X1144521Y1259277D02*
X1141321D01*
G01X1153518Y1400344D02*
X1147518D01*
Y1388344D01*
X1153518D01*
Y1400344D01*
G01X1146775Y1434327D02*
Y1422327D01*
G01X1152775Y1434327D02*
X1146775D01*
G01Y1422327D02*
X1152775D01*
G01X1138369Y1434327D02*
Y1422327D01*
G01X1144369Y1434327D02*
X1138369D01*
G01X1144369Y1422327D02*
Y1434327D01*
G01X1138369Y1422327D02*
X1144369D01*
G01X1159754Y1442544D02*
Y1448544D01*
X1147754D01*
Y1442544D01*
X1159754D01*
G01X1144087Y1589838D02*
Y1583638D01*
X1147287D01*
Y1589838D01*
X1144087D01*
G01X1153287Y1575638D02*
Y1581838D01*
X1150087D01*
Y1575638D01*
X1153287D01*
G01X1143287D02*
Y1581838D01*
X1140087D01*
Y1575638D01*
X1143287D01*
G01X1140087Y1589838D02*
Y1583638D01*
X1143287D01*
Y1589838D01*
X1140087D01*
G01X1150087D02*
Y1583638D01*
X1153287D01*
Y1589838D01*
X1150087D01*
G01X1147287Y1575638D02*
Y1581838D01*
X1144087D01*
Y1575638D01*
X1147287D01*
G01X1164944Y179685D02*
X1176944D01*
G01X1164944Y185685D02*
Y179685D01*
G01X1176944Y185685D02*
X1164944D01*
G01X1166262Y188288D02*
X1176462D01*
G01X1166262Y192888D02*
Y188288D01*
G01X1176462Y192888D02*
X1166262D01*
G01X1165940Y195442D02*
X1176140D01*
G01X1165940Y200042D02*
Y195442D01*
G01X1176140Y200042D02*
X1165940D01*
G01Y203542D02*
X1176140D01*
G01X1165940Y208142D02*
Y203542D01*
G01X1176140Y208142D02*
X1165940D01*
G01X1155067Y587422D02*
Y593622D01*
G01X1151867Y587422D02*
X1155067D01*
G01X1151867Y593622D02*
Y587422D01*
G01X1151937Y601412D02*
X1155137D01*
G01X1151937Y607612D02*
Y601412D01*
G01X1155137Y607612D02*
X1151937D01*
G01X1155137Y601412D02*
Y607612D01*
G01X1151877Y594442D02*
X1155077D01*
G01X1151877Y600642D02*
Y594442D01*
G01X1155077Y600642D02*
X1151877D01*
G01X1155077Y594442D02*
Y600642D01*
G01X1155067Y593622D02*
X1151867D01*
G01X1167677Y767925D02*
X1164477D01*
G01X1167677Y761725D02*
Y767925D01*
G01X1164477Y761725D02*
X1167677D01*
G01X1164477Y767925D02*
Y761725D01*
G01X1153641Y1258544D02*
Y1255344D01*
G01X1159841Y1258544D02*
X1153641D01*
G01X1159841Y1255344D02*
Y1258544D01*
G01X1153641Y1255344D02*
X1159841D01*
G01X1162291Y1253504D02*
X1165491D01*
G01X1162291Y1259704D02*
Y1253504D01*
G01X1165491D02*
Y1259704D01*
G01X1159741Y1259944D02*
Y1271944D01*
G01X1153741Y1259944D02*
X1159741D01*
G01X1153741Y1271944D02*
Y1259944D01*
G01X1159741Y1271944D02*
X1153741D01*
G01X1165491Y1259704D02*
X1162291D01*
G01X1164931Y1400344D02*
X1158931D01*
Y1388344D01*
X1164931D01*
Y1400344D01*
G01X1184554Y1383870D02*
Y1419566D01*
X1166838D01*
Y1383870D01*
X1184554D01*
G01X1158152Y1390685D02*
Y1396885D01*
X1154952D01*
Y1390685D01*
X1158152D01*
G01X1152775Y1422327D02*
Y1434327D01*
G01X1162043Y1429130D02*
X1165243D01*
G01X1162043Y1435330D02*
Y1429130D01*
G01X1165243Y1435330D02*
X1162043D01*
G01X1165243Y1429130D02*
Y1435330D01*
G01X1165772Y1442429D02*
Y1448629D01*
X1162572D01*
Y1442429D01*
X1165772D01*
G01X1163495Y1589838D02*
Y1583638D01*
X1166695D01*
Y1589838D01*
X1163495D01*
G01X1154087D02*
Y1583638D01*
X1157287D01*
Y1589838D01*
X1154087D01*
G01X1162695Y1575638D02*
Y1581838D01*
X1159495D01*
Y1575638D01*
X1162695D01*
G01X1159495Y1589838D02*
Y1583638D01*
X1162695D01*
Y1589838D01*
X1159495D01*
G01X1157287Y1575638D02*
Y1581838D01*
X1154087D01*
Y1575638D01*
X1157287D01*
G01X1166695D02*
Y1581838D01*
X1163495D01*
Y1575638D01*
X1166695D01*
G01X1158710Y1632860D02*
Y1626660D01*
X1161910D01*
Y1632860D01*
X1158710D01*
G01X1176944Y179685D02*
Y185685D01*
G01X1183573Y197486D02*
X1195573D01*
G01X1183573Y203486D02*
Y197486D01*
G01X1183569Y190180D02*
X1195569D01*
G01X1183569Y196180D02*
Y190180D01*
G01X1195569Y196180D02*
X1183569D01*
G01X1171362Y192888D02*
Y188288D01*
G01X1176462D02*
Y192888D01*
G01X1171040Y200042D02*
Y195442D01*
G01X1176140D02*
Y200042D01*
G01X1195573Y203486D02*
X1183573D01*
G01X1171040Y208142D02*
Y203542D01*
G01X1176140D02*
Y208142D01*
G01X1180635Y582217D02*
Y579995D01*
X1180482Y579530D01*
X1180175Y579220D01*
X1179792Y579117D01*
X1179409Y579220D01*
X1179102Y579530D01*
X1178949Y579995D01*
Y582217D01*
G01X1176692Y579117D02*
Y582217D01*
X1177152Y581597D01*
G01Y579117D02*
X1176232D01*
G01X1174435Y579582D02*
X1174205Y579324D01*
X1173937Y579169D01*
X1173592Y579117D01*
X1173247Y579220D01*
X1172979Y579427D01*
X1172787Y579789D01*
X1172749Y580202D01*
X1172825Y580615D01*
X1173017Y580874D01*
X1173285Y581080D01*
X1173554Y581132D01*
X1173822Y581080D01*
X1174167Y580874D01*
X1174052Y582217D01*
X1173017D01*
G01X1175458Y591841D02*
X1178525Y588774D01*
G01X1172391D02*
X1175458Y591841D01*
G01X1168658Y588774D02*
X1172391D01*
G01X1168658Y608380D02*
Y588774D01*
G01X1182258D02*
Y608380D01*
G01X1178525Y588774D02*
X1182258D01*
G01Y608380D02*
X1168658D01*
G01X1171142Y769307D02*
X1174342D01*
G01X1171142Y775507D02*
Y769307D01*
G01X1174342D02*
Y775507D01*
G01X1179277Y765595D02*
X1176077D01*
G01X1179277Y759395D02*
Y765595D01*
G01X1176077Y759395D02*
X1179277D01*
G01X1176077Y765595D02*
Y759395D01*
G01X1174342Y775507D02*
X1171142D01*
G01X1178242Y777207D02*
X1181442D01*
G01X1178242Y783407D02*
Y777207D01*
G01X1181442Y783407D02*
X1178242D01*
G01X1181442Y777207D02*
Y783407D01*
G01X1169900Y1021962D02*
Y1018762D01*
G01X1176100Y1021962D02*
X1169900D01*
G01X1176100Y1018762D02*
Y1021962D01*
G01X1169900Y1018762D02*
X1176100D01*
G01X1169900Y1014762D02*
X1176100D01*
G01D02*
Y1017962D01*
G01X1169900D02*
Y1014762D01*
G01X1176100Y1017962D02*
X1169900D01*
G01X1183341Y1258544D02*
Y1255344D01*
G01X1189541Y1258544D02*
X1183341D01*
G01Y1255344D02*
X1189541D01*
G01X1174249Y1252762D02*
Y1258962D01*
G01X1171049Y1252762D02*
X1174249D01*
G01X1171049Y1258962D02*
Y1252762D01*
G01X1181163Y1252091D02*
X1177963D01*
G01X1181163Y1245891D02*
Y1252091D01*
G01X1177963Y1245891D02*
X1181163D01*
G01X1177963Y1252091D02*
Y1245891D01*
G01X1183441Y1259944D02*
X1189441D01*
G01X1183441Y1271944D02*
Y1259944D01*
G01X1189441Y1271944D02*
X1183441D01*
G01X1175741Y1259944D02*
Y1271944D01*
G01X1169741Y1259944D02*
X1175741D01*
G01X1169741Y1271944D02*
Y1259944D01*
G01X1175741Y1271944D02*
X1169741D01*
G01X1174249Y1258962D02*
X1171049D01*
G01X1174373Y1377702D02*
X1176613D01*
G01X1175400Y1376077D02*
Y1379327D01*
G01X1175396Y1422405D02*
Y1424831D01*
G01X1176512Y1434327D02*
Y1422327D01*
G01X1182512Y1434327D02*
X1176512D01*
G01X1182512Y1422327D02*
Y1434327D01*
G01X1176512Y1422327D02*
X1182512D01*
G01X1173495Y1589838D02*
Y1583638D01*
X1176695D01*
Y1589838D01*
X1173495D01*
G01X1172695Y1575638D02*
Y1581838D01*
X1169495D01*
Y1575638D01*
X1172695D01*
G01X1169495Y1589838D02*
Y1583638D01*
X1172695D01*
Y1589838D01*
X1169495D01*
G01X1176695Y1575638D02*
Y1581838D01*
X1173495D01*
Y1575638D01*
X1176695D01*
G01X1190360Y183282D02*
Y187882D01*
G01X1185260D02*
Y183282D01*
G01X1195460D02*
Y187882D01*
G01X1185260Y183282D02*
X1195460D01*
G01X1195573Y197486D02*
Y203486D01*
G01X1195569Y190180D02*
Y196180D01*
G01X1195460Y187882D02*
X1185260D01*
G01X1189838Y211833D02*
Y216433D01*
G01X1184738D02*
Y211833D01*
G01X1194938Y216433D02*
X1184738D01*
G01X1194938Y211833D02*
Y216433D01*
G01X1184738Y211833D02*
X1194938D01*
G01X1189838Y206433D02*
Y211033D01*
G01X1184738D02*
Y206433D01*
G01X1194938Y211033D02*
X1184738D01*
G01X1194938Y206433D02*
Y211033D01*
G01X1184738Y206433D02*
X1194938D01*
G01X1187058Y221962D02*
Y218762D01*
G01X1193258Y221962D02*
X1187058D01*
G01X1193258Y218762D02*
Y221962D01*
G01X1187058Y218762D02*
X1193258D01*
G01X1191673Y590314D02*
Y587114D01*
G01X1197873Y590314D02*
X1191673D01*
G01X1197873Y587114D02*
Y590314D01*
G01X1191673Y587114D02*
X1197873D01*
G01X1200008D02*
X1206208D01*
G01X1200008Y590314D02*
Y587114D01*
G01X1206208Y590314D02*
X1200008D01*
G01X1199787Y600733D02*
Y597533D01*
G01X1205987Y600733D02*
X1199787D01*
G01Y597533D02*
X1205987D01*
G01X1200147Y607205D02*
Y604005D01*
G01X1206347Y607205D02*
X1200147D01*
G01Y604005D02*
X1206347D01*
G01X1195796Y594221D02*
X1198996D01*
G01X1195796Y600421D02*
Y594221D01*
G01X1198996Y600421D02*
X1195796D01*
G01X1198996Y594221D02*
Y600421D01*
G01X1195796Y601236D02*
X1198996D01*
G01X1195796Y607436D02*
Y601236D01*
G01X1198996Y607436D02*
X1195796D01*
G01X1198996Y601236D02*
Y607436D01*
G01X1202097Y769715D02*
X1198897D01*
G01Y763515D02*
X1202097D01*
G01X1198897Y769715D02*
Y763515D01*
G01X1196697Y769715D02*
X1193497D01*
G01X1196697Y763515D02*
Y769715D01*
G01X1193497Y763515D02*
X1196697D01*
G01X1193497Y769715D02*
Y763515D01*
G01X1196697Y760807D02*
X1193497D01*
G01X1196697Y754607D02*
Y760807D01*
G01X1193497Y754607D02*
X1196697D01*
G01X1193497Y760807D02*
Y754607D01*
G01X1201197Y760779D02*
X1197997D01*
G01Y754579D02*
X1201197D01*
G01X1197997Y760779D02*
Y754579D01*
G01X1199641Y1011244D02*
X1205641D01*
G01X1199641Y1023244D02*
Y1011244D01*
G01X1205641Y1023244D02*
X1199641D01*
G01X1189541Y1255344D02*
Y1258544D01*
G01X1198079Y1253049D02*
X1201279D01*
G01X1198079Y1259249D02*
Y1253049D01*
G01X1200439Y1245336D02*
X1204823Y1249720D01*
G01X1198177Y1247598D02*
X1200439Y1245336D01*
G01X1202561Y1251982D02*
X1198177Y1247598D01*
G01X1196601Y1254540D02*
Y1257740D01*
G01X1190401Y1254540D02*
X1196601D01*
G01X1190401Y1257740D02*
Y1254540D01*
G01X1196601Y1257740D02*
X1190401D01*
G01X1199441Y1259944D02*
X1205441D01*
G01X1199441Y1271944D02*
Y1259944D01*
G01X1205441Y1271944D02*
X1199441D01*
G01X1189441Y1259944D02*
Y1271944D01*
G01X1201279Y1259249D02*
X1198079D01*
G01X1196280Y1399221D02*
X1190280D01*
Y1387221D01*
X1196280D01*
Y1399221D01*
G01X1189491Y1390424D02*
Y1396624D01*
X1186291D01*
Y1390424D01*
X1189491D01*
G01X1190692Y1434872D02*
X1202692D01*
G01X1190692Y1440872D02*
Y1434872D01*
G01X1184918Y1434327D02*
Y1422327D01*
G01X1190918Y1434327D02*
X1184918D01*
G01X1190918Y1422327D02*
Y1434327D01*
G01X1184918Y1422327D02*
X1190918D01*
G01X1202692Y1440872D02*
X1190692D01*
G01X1213193Y119362D02*
Y122562D01*
G01X1206993Y119362D02*
X1213193D01*
G01X1206993Y122562D02*
Y119362D01*
G01X1214435Y119402D02*
X1220635D01*
G01X1214435Y122602D02*
Y119402D01*
G01X1215633Y128542D02*
Y125342D01*
G01X1221833Y128542D02*
X1215633D01*
G01Y125342D02*
X1221833D01*
G01X1213193Y122562D02*
X1206993D01*
G01X1220635Y122602D02*
X1214435D01*
G01X1215600Y133000D02*
X1221800D01*
Y136200D01*
X1215600D01*
Y133000D01*
G01X1215630Y129210D02*
X1221830D01*
Y132410D01*
X1215630D01*
Y129210D01*
G01X1206208Y587114D02*
Y590314D01*
G01X1205987Y597533D02*
Y600733D01*
G01X1206347Y604005D02*
Y607205D01*
G01X1210137Y752905D02*
X1206937D01*
G01X1210137Y746705D02*
Y752905D01*
G01X1206937Y746705D02*
X1210137D01*
G01X1206937Y752905D02*
Y746705D01*
G01X1214137Y752905D02*
X1210937D01*
G01X1214137Y746705D02*
Y752905D01*
G01X1210937Y746705D02*
X1214137D01*
G01X1210937Y752905D02*
Y746705D01*
G01X1210847Y769705D02*
X1207647D01*
G01X1210847Y763505D02*
Y769705D01*
G01X1207647Y763505D02*
X1210847D01*
G01X1207647Y769705D02*
Y763505D01*
G01X1214537Y761405D02*
X1211337D01*
G01X1214537Y755205D02*
Y761405D01*
G01X1211337Y755205D02*
X1214537D01*
G01X1211337Y761405D02*
Y755205D01*
G01X1210537Y761405D02*
X1207337D01*
G01X1210537Y755205D02*
Y761405D01*
G01X1207337Y755205D02*
X1210537D01*
G01X1207337Y761405D02*
Y755205D01*
G01X1206097Y769715D02*
X1202897D01*
G01X1206097Y763515D02*
Y769715D01*
G01X1202897Y763515D02*
X1206097D01*
G01X1202897Y769715D02*
Y763515D01*
G01X1202097D02*
Y769715D01*
G01X1201197Y754579D02*
Y760779D01*
G01X1213152Y993344D02*
Y981344D01*
G01D02*
X1219152D01*
G01Y993344D02*
X1213152D01*
G01X1212841Y1011244D02*
X1218841D01*
G01X1212841Y1023244D02*
Y1011244D01*
G01X1205641D02*
Y1023244D01*
G01X1218841D02*
X1212841D01*
G01X1214922Y1233261D02*
X1217162D01*
G01X1215949Y1231636D02*
Y1234886D01*
G01X1210993Y1238232D02*
Y1241332D01*
X1210227D01*
X1209920Y1241177D01*
X1209690Y1240970D01*
X1209498Y1240660D01*
X1209345Y1240299D01*
X1209307Y1239782D01*
X1209345Y1239265D01*
X1209498Y1238904D01*
X1209690Y1238594D01*
X1209920Y1238387D01*
X1210227Y1238232D01*
X1210993D01*
G01X1206590D02*
Y1241332D01*
X1208008Y1239110D01*
X1206092D01*
G01X1204678Y1240815D02*
X1204448Y1241125D01*
X1204180Y1241280D01*
X1203873Y1241332D01*
X1203490Y1241229D01*
X1203222Y1240970D01*
X1203145Y1240660D01*
X1203183Y1240350D01*
X1203337Y1240092D01*
X1204103Y1239575D01*
X1204448Y1239214D01*
X1204678Y1238697D01*
X1204755Y1238232D01*
X1203145D01*
G01X1213393Y1236611D02*
X1218905D01*
G01X1213393Y1252759D02*
Y1236611D01*
G01X1213500Y1257493D02*
Y1255067D01*
G01X1216149Y1245448D02*
X1218118Y1243480D01*
G01X1214180D02*
X1216149Y1245448D01*
G01X1218118Y1243480D02*
X1214180D01*
G01X1218118Y1245842D02*
X1214180D01*
G01X1213399Y1253911D02*
Y1253411D01*
G01X1218899Y1253911D02*
X1213399D01*
G01X1213649Y1253161D02*
X1218899D01*
G01X1213649Y1252761D02*
Y1253161D01*
G01X1213399Y1252761D02*
X1213649D01*
G01X1213399Y1253461D02*
Y1252761D01*
G01X1218899Y1253461D02*
X1213399D01*
G01X1218905Y1252759D02*
X1213393D01*
G01X1210915Y1252338D02*
X1207715D01*
G01X1210915Y1246138D02*
Y1252338D01*
G01X1207715Y1246138D02*
X1210915D01*
G01X1207715Y1252338D02*
Y1246138D01*
G01X1215408Y1255189D02*
X1221608D01*
G01X1215408Y1258389D02*
Y1255189D01*
G01X1221608Y1258389D02*
X1215408D01*
G01X1201279Y1253049D02*
Y1259249D01*
G01X1204823Y1249720D02*
X1202561Y1251982D01*
G01X1205441Y1259944D02*
Y1271944D01*
G01X1213141Y1259944D02*
X1219141D01*
G01X1213141Y1271944D02*
Y1259944D01*
G01X1219141Y1271944D02*
X1213141D01*
G01X1202692Y1434872D02*
Y1440872D01*
G01X1227104Y104462D02*
X1230304D01*
G01X1227104Y110662D02*
Y104462D01*
G01X1230304Y110662D02*
X1227104D01*
G01X1230304Y104462D02*
Y110662D01*
G01X1225993Y118562D02*
Y115362D01*
G01X1232193Y118562D02*
X1225993D01*
G01X1232193Y115362D02*
Y118562D01*
G01X1225993Y115362D02*
X1232193D01*
G01X1220635Y119402D02*
Y122602D01*
G01X1226993Y135862D02*
Y132662D01*
G01X1233193Y135862D02*
X1226993D01*
G01Y132662D02*
X1233193D01*
G01X1221833Y125342D02*
Y128542D01*
G01X1226993Y128362D02*
X1233193D01*
G01X1226993Y131562D02*
Y128362D01*
G01X1233193Y131562D02*
X1226993D01*
G01Y139362D02*
X1233193D01*
G01X1226993Y142562D02*
Y139362D01*
G01X1233193Y142562D02*
X1226993D01*
G01Y143362D02*
X1233193D01*
G01X1226993Y146562D02*
Y143362D01*
G01X1233193Y146562D02*
X1226993D01*
G01X1227523Y151012D02*
X1233723D01*
G01X1227523Y154212D02*
Y151012D01*
G01Y158272D02*
Y155072D01*
G01X1233723Y158272D02*
X1227523D01*
G01Y155072D02*
X1233723D01*
G01Y154212D02*
X1227523D01*
G01X1228910Y194082D02*
Y190882D01*
G01X1235110Y194082D02*
X1228910D01*
G01Y190882D02*
X1235110D01*
G01X1230820Y204262D02*
Y207462D01*
G01X1224620Y204262D02*
X1230820D01*
G01X1224620Y207462D02*
Y204262D01*
G01X1230820Y207462D02*
X1224620D01*
G01X1230820Y216262D02*
Y219462D01*
G01X1224620Y216262D02*
X1230820D01*
G01X1224620Y219462D02*
Y216262D01*
G01X1230820Y208262D02*
Y211462D01*
G01X1224620Y208262D02*
X1230820D01*
G01X1224620Y211462D02*
Y208262D01*
G01X1230820Y211462D02*
X1224620D01*
G01X1230820Y212262D02*
Y215462D01*
G01X1224620Y212262D02*
X1230820D01*
G01X1224620Y215462D02*
Y212262D01*
G01X1230820Y215462D02*
X1224620D01*
G01X1230820Y219462D02*
X1224620D01*
G01X1227260Y759665D02*
X1230460D01*
G01X1227260Y765865D02*
Y759665D01*
G01X1230460Y765865D02*
X1227260D01*
G01X1230460Y759665D02*
Y765865D01*
G01X1221107Y758825D02*
X1224307D01*
G01X1221107Y765025D02*
Y758825D01*
G01X1224307Y765025D02*
X1221107D01*
G01X1224307Y758825D02*
Y765025D01*
G01X1229241Y993344D02*
Y981344D01*
G01D02*
X1235241D01*
G01X1219152D02*
Y993344D01*
G01X1235241D02*
X1229241D01*
G01X1229341Y1011244D02*
X1235341D01*
G01X1229341Y1023244D02*
Y1011244D01*
G01X1227241D02*
Y1023244D01*
G01X1221241Y1011244D02*
X1227241D01*
G01X1221241Y1023244D02*
Y1011244D01*
G01X1218841D02*
Y1023244D01*
G01X1235341D02*
X1229341D01*
G01X1227241D02*
X1221241D01*
G01X1218905Y1236611D02*
Y1252759D01*
G01X1225393Y1241486D02*
X1222193D01*
G01X1225393Y1235286D02*
Y1241486D01*
G01X1222193Y1235286D02*
X1225393D01*
G01X1222193Y1241486D02*
Y1235286D01*
G01X1225393Y1242286D02*
Y1248486D01*
G01X1222193Y1242286D02*
X1225393D01*
G01X1222193Y1248486D02*
Y1242286D01*
G01X1218899Y1253161D02*
Y1253911D01*
G01Y1252811D02*
Y1253461D01*
G01X1218799Y1252811D02*
X1218899D01*
G01X1221608Y1255189D02*
Y1258389D01*
G01X1232281Y1251390D02*
X1229081D01*
G01X1232281Y1245190D02*
Y1251390D01*
G01X1229081Y1245190D02*
X1232281D01*
G01X1229081Y1251390D02*
Y1245190D01*
G01X1225393Y1248486D02*
X1222193D01*
G01X1232281Y1253078D02*
Y1259278D01*
G01X1229081Y1253078D02*
X1232281D01*
G01X1229081Y1259278D02*
Y1253078D01*
G01X1229141Y1259944D02*
X1235141D01*
G01X1229141Y1271944D02*
Y1259944D01*
G01X1235141Y1271944D02*
X1229141D01*
G01X1219141Y1259944D02*
Y1271944D01*
G01X1232281Y1259278D02*
X1229081D01*
G01X1287607Y1647480D02*
Y1654980D01*
X1285367D01*
X1284620Y1654605D01*
X1284060Y1653730D01*
X1283873Y1652730D01*
X1284060Y1651730D01*
X1284527Y1650980D01*
X1285367Y1650605D01*
X1287607D01*
G01X1280107Y1647480D02*
Y1654980D01*
X1277773D01*
X1277027Y1654605D01*
X1276560Y1654105D01*
X1276373Y1653105D01*
X1276560Y1652105D01*
X1277120Y1651480D01*
X1277773Y1651105D01*
X1280107D01*
G01X1277773D02*
X1276373Y1647480D01*
G01X1268873D02*
X1272607D01*
Y1654980D01*
X1268873D01*
G01X1270367Y1651355D02*
X1272607D01*
G01X1265200Y1648480D02*
X1264453Y1647855D01*
X1263613Y1647480D01*
X1262867D01*
X1262120Y1647855D01*
X1261560Y1648480D01*
X1261280Y1649355D01*
X1261467Y1650230D01*
X1261933Y1650980D01*
X1262773Y1651480D01*
X1263893Y1651730D01*
X1264547Y1652230D01*
X1264827Y1653105D01*
X1264640Y1653980D01*
X1264173Y1654605D01*
X1263520Y1654980D01*
X1262867D01*
X1262213Y1654730D01*
X1261653Y1654105D01*
G01X1257700Y1648480D02*
X1256953Y1647855D01*
X1256113Y1647480D01*
X1255367D01*
X1254620Y1647855D01*
X1254060Y1648480D01*
X1253780Y1649355D01*
X1253967Y1650230D01*
X1254433Y1650980D01*
X1255273Y1651480D01*
X1256393Y1651730D01*
X1257047Y1652230D01*
X1257327Y1653105D01*
X1257140Y1653980D01*
X1256673Y1654605D01*
X1256020Y1654980D01*
X1255367D01*
X1254713Y1654730D01*
X1254153Y1654105D01*
G01X1249453Y1649980D02*
X1247027D01*
G01X1242513Y1647480D02*
Y1654980D01*
X1238967D01*
G01X1240273Y1651355D02*
X1242513D01*
G01X1234360Y1654980D02*
X1232120D01*
G01X1233240D02*
Y1647480D01*
G01X1234360D02*
X1232120D01*
G01X1225740Y1654980D02*
Y1647480D01*
G01X1227887Y1654980D02*
X1223593D01*
G01X1312205Y1646023D02*
X1222048D01*
G01D02*
Y1781456D01*
G01X1234767Y1681683D02*
Y1678583D01*
X1233233D01*
G01X1234997Y1673859D02*
Y1676959D01*
X1234000Y1674376D01*
X1233003Y1676959D01*
Y1673859D01*
G01X1234882Y1669135D02*
Y1672235D01*
X1233118Y1669135D01*
Y1672235D01*
G01X1234460Y1695857D02*
X1233540D01*
G01X1234000D02*
Y1692757D01*
G01X1234460D02*
X1233540D01*
G01X1234767Y1688652D02*
X1234575Y1688342D01*
X1234345Y1688135D01*
X1234077Y1688032D01*
X1233770Y1688135D01*
X1233540Y1688342D01*
X1233310Y1688652D01*
X1233233Y1689065D01*
Y1691132D01*
G01X1234843Y1683308D02*
Y1686408D01*
G01X1233387D02*
X1234843Y1684496D01*
G01X1233157Y1683308D02*
X1234192Y1685375D01*
G01X1234799Y1697052D02*
Y1700152D01*
G01X1233189D02*
Y1697052D01*
G01Y1698602D02*
X1234799D01*
G01X1233233Y1711654D02*
X1234767D01*
Y1714754D01*
X1233233D01*
G01X1233847Y1713256D02*
X1234767D01*
G01X1234728Y1706930D02*
Y1710030D01*
X1233272D01*
G01X1233808Y1708532D02*
X1234728D01*
G01X1233664Y1703402D02*
X1232897D01*
Y1702472D01*
X1233127Y1702162D01*
X1233396Y1701955D01*
X1233779Y1701852D01*
X1234162Y1701955D01*
X1234431Y1702162D01*
X1234661Y1702472D01*
X1234814Y1702834D01*
X1234891Y1703247D01*
Y1703609D01*
X1234814Y1703919D01*
X1234661Y1704280D01*
X1234431Y1704590D01*
X1234201Y1704797D01*
X1233894Y1704952D01*
X1233626D01*
X1233319Y1704849D01*
X1233089Y1704642D01*
G01X1234843Y1716379D02*
Y1719479D01*
X1234077D01*
X1233770Y1719324D01*
X1233540Y1719117D01*
X1233348Y1718807D01*
X1233195Y1718446D01*
X1233157Y1717929D01*
X1233195Y1717412D01*
X1233348Y1717051D01*
X1233540Y1716741D01*
X1233770Y1716534D01*
X1234077Y1716379D01*
X1234843D01*
G01X1233693Y1727481D02*
X1233540Y1727636D01*
X1233425Y1727895D01*
X1233348Y1728256D01*
X1233425Y1728566D01*
X1233578Y1728773D01*
X1233847Y1728928D01*
X1234882D01*
Y1725828D01*
X1233617D01*
X1233348Y1726035D01*
X1233195Y1726345D01*
X1233118Y1726706D01*
X1233195Y1727068D01*
X1233425Y1727378D01*
X1233693Y1727481D01*
X1234882D01*
G01X1233157Y1723945D02*
X1233387Y1724100D01*
X1233655Y1724203D01*
X1233962D01*
X1234307Y1724048D01*
X1234575Y1723790D01*
X1234767Y1723480D01*
X1234920Y1722963D01*
X1234958Y1722498D01*
X1234882Y1722033D01*
X1234767Y1721723D01*
X1234537Y1721413D01*
X1234268Y1721206D01*
X1234000Y1721103D01*
X1233732D01*
X1233463Y1721206D01*
X1233233Y1721361D01*
X1233042Y1721568D01*
G01X1234752Y1731052D02*
X1233794Y1734152D01*
X1232836Y1731052D01*
G01X1233181Y1732137D02*
X1234407D01*
G01X1222048Y1781456D02*
X1312205D01*
G01X1248485Y121707D02*
Y118507D01*
G01D02*
X1254685D01*
G01X1233193Y132662D02*
Y135862D01*
G01Y128362D02*
Y131562D01*
G01X1248486Y125707D02*
Y122507D01*
G01X1254686Y125707D02*
X1248486D01*
G01Y122507D02*
X1254686D01*
G01X1254685Y121707D02*
X1248485D01*
G01X1233193Y139362D02*
Y142562D01*
G01Y143362D02*
Y146562D01*
G01X1233723Y151012D02*
Y154212D01*
G01X1249461Y137845D02*
X1253845Y142229D01*
X1251583Y144491D01*
X1247199Y140107D01*
X1249461Y137845D01*
G01X1247685Y153892D02*
X1249947Y151630D01*
G01X1252069Y158276D02*
X1247685Y153892D01*
G01X1233723Y155072D02*
Y158272D01*
G01X1235110Y190882D02*
Y194082D01*
G01X1243693Y199862D02*
Y203062D01*
G01X1237493Y199862D02*
X1243693D01*
G01X1237493Y203062D02*
Y199862D01*
G01X1237620Y194962D02*
Y191762D01*
G01X1243820Y194962D02*
X1237620D01*
G01X1243820Y191762D02*
Y194962D01*
G01X1237620Y191762D02*
X1243820D01*
G01X1243693Y203862D02*
Y207062D01*
G01X1237493Y203862D02*
X1243693D01*
G01X1237493Y207062D02*
Y203862D01*
G01X1243693Y207062D02*
X1237493D01*
G01X1243693Y207862D02*
Y211062D01*
G01X1237493Y207862D02*
X1243693D01*
G01X1237493Y211062D02*
Y207862D01*
G01X1243693Y211062D02*
X1237493D01*
G01X1243693Y211862D02*
Y215062D01*
G01X1237493Y211862D02*
X1243693D01*
G01X1237493Y215062D02*
Y211862D01*
G01X1243693Y215062D02*
X1237493D01*
G01Y219062D02*
Y215862D01*
G01X1243693D02*
Y219062D01*
G01X1237493Y215862D02*
X1243693D01*
G01Y203062D02*
X1237493D01*
G01X1243693Y219062D02*
X1237493D01*
G01X1237520Y223162D02*
Y219962D01*
G01X1243720Y223162D02*
X1237520D01*
G01X1243720Y219962D02*
Y223162D01*
G01X1237520Y219962D02*
X1243720D01*
G01X1247901Y253798D02*
X1258101D01*
G01X1247901Y258398D02*
Y253798D01*
G01X1258101Y258398D02*
X1247901D01*
G01X1256938Y269488D02*
G03I-9300J0D01*
G01X1247522Y751307D02*
X1250722D01*
G01X1247522Y757507D02*
Y751307D01*
G01X1243998Y749717D02*
Y755917D01*
G01X1240798Y749717D02*
X1243998D01*
G01X1240798Y755917D02*
Y749717D01*
G01X1250722Y757507D02*
X1247522D01*
G01X1243998Y755917D02*
X1240798D01*
G01X1240660Y758865D02*
X1243860D01*
G01X1240660Y765065D02*
Y758865D01*
G01X1243860Y765065D02*
X1240660D01*
G01X1243860Y758865D02*
Y765065D01*
G01X1251860D02*
X1248660D01*
G01Y758865D02*
X1251860D01*
G01X1248660Y765065D02*
Y758865D01*
G01X1247860Y765065D02*
X1244660D01*
G01X1247860Y758865D02*
Y765065D01*
G01X1244660Y758865D02*
X1247860D01*
G01X1244660Y765065D02*
Y758865D01*
G01X1233760D02*
X1236960D01*
G01X1233760Y765065D02*
Y758865D01*
G01X1236960Y765065D02*
X1233760D01*
G01X1236960Y758865D02*
Y765065D01*
G01X1244377Y905885D02*
Y909085D01*
G01X1238177Y905885D02*
X1244377D01*
G01X1238177Y909085D02*
Y905885D01*
G01X1244377Y909085D02*
X1238177D01*
G01X1235241Y981344D02*
Y993344D01*
G01X1235341Y1011244D02*
Y1023244D01*
G01X1235141Y1259944D02*
Y1271944D01*
G01X1238753Y1665802D02*
Y1668902D01*
X1239213Y1668282D01*
G01Y1665802D02*
X1238293D01*
G01X1247355Y1668385D02*
X1247125Y1668695D01*
X1246857Y1668850D01*
X1246550Y1668902D01*
X1246167Y1668799D01*
X1245899Y1668540D01*
X1245822Y1668230D01*
X1245860Y1667920D01*
X1246014Y1667662D01*
X1246780Y1667145D01*
X1247125Y1666784D01*
X1247355Y1666267D01*
X1247432Y1665802D01*
X1245822D01*
G01X1260783Y108260D02*
Y102060D01*
G01D02*
X1263983D01*
G01D02*
Y108260D01*
G01X1265123D02*
Y102060D01*
G01D02*
X1268323D01*
G01X1263983Y108260D02*
X1260783D01*
G01X1268323D02*
X1265123D01*
G01X1254685Y118507D02*
Y121707D01*
G01X1256595Y124737D02*
X1259795D01*
G01X1256595Y130937D02*
Y124737D01*
G01X1259795Y130937D02*
X1256595D01*
G01X1259795Y124737D02*
Y130937D01*
G01X1254686Y122507D02*
Y125707D01*
G01X1249919Y137407D02*
X1252181Y135145D01*
G01D02*
X1256565Y139529D01*
G01X1263532Y139139D02*
X1267916Y143523D01*
G01X1261270Y141401D02*
X1263532Y139139D01*
G01X1265654Y145785D02*
X1261270Y141401D01*
G01X1266221Y148474D02*
X1263959Y150736D01*
G01X1261837Y144090D02*
X1266221Y148474D01*
G01X1259575Y146352D02*
X1261837Y144090D01*
G01X1263959Y150736D02*
X1259575Y146352D01*
G01X1254303Y141791D02*
X1249919Y137407D01*
G01X1256565Y139529D02*
X1254303Y141791D01*
G01X1264172Y152483D02*
X1268556Y156867D01*
G01X1261910Y154745D02*
X1264172Y152483D01*
G01X1264710Y151675D02*
X1266972Y149413D01*
G01X1269094Y156059D02*
X1264710Y151675D01*
G01X1249947Y151630D02*
X1254331Y156014D01*
G01X1254256Y160240D02*
X1256518Y157978D01*
G01X1258640Y164624D02*
X1254256Y160240D01*
G01X1260902Y162362D02*
X1258640Y164624D01*
G01X1256518Y157978D02*
X1260902Y162362D01*
G01X1266294Y159129D02*
X1261910Y154745D01*
G01X1254331Y156014D02*
X1252069Y158276D01*
G01X1262114Y225982D02*
X1258914D01*
G01X1262114Y219782D02*
Y225982D01*
G01X1258914Y219782D02*
X1262114D01*
G01X1258914Y225982D02*
Y219782D01*
G01X1258944Y226422D02*
X1262144D01*
G01X1258944Y232622D02*
Y226422D01*
G01X1262144Y232622D02*
X1258944D01*
G01X1262144Y226422D02*
Y232622D01*
G01X1266333Y269606D02*
X1260333D01*
Y257606D01*
X1266333D01*
Y269606D01*
G01X1258101Y253798D02*
Y258398D01*
G01X1253001D02*
Y253798D01*
G01X1261598Y737117D02*
X1258398D01*
G01X1261598Y730917D02*
Y737117D01*
G01X1258398Y730917D02*
X1261598D01*
G01X1258398Y737117D02*
Y730917D01*
G01X1254593Y729065D02*
X1257793D01*
G01X1254593Y735265D02*
Y729065D01*
G01X1257793Y735265D02*
X1254593D01*
G01X1257793Y729065D02*
Y735265D01*
G01X1251247Y736695D02*
X1254447D01*
G01X1251247Y742895D02*
Y736695D01*
G01X1254447D02*
Y742895D01*
G01X1265387Y737115D02*
X1262187D01*
G01X1265387Y730915D02*
Y737115D01*
G01X1262187Y730915D02*
X1265387D01*
G01X1262187Y737115D02*
Y730915D01*
G01X1250722Y751307D02*
Y757507D01*
G01X1254447Y750095D02*
X1251247D01*
G01X1254447Y743895D02*
Y750095D01*
G01X1251247Y743895D02*
X1254447D01*
G01X1251247Y750095D02*
Y743895D01*
G01X1251053Y754049D02*
Y750849D01*
G01X1257253Y754049D02*
X1251053D01*
G01X1257253Y750849D02*
Y754049D01*
G01X1251053Y750849D02*
X1257253D01*
G01X1261507Y740185D02*
Y743385D01*
G01X1255307Y740185D02*
X1261507D01*
G01X1255307Y743385D02*
Y740185D01*
G01X1261507Y743385D02*
X1255307D01*
G01X1254447Y742895D02*
X1251247D01*
G01X1262337Y740865D02*
X1265537D01*
G01X1262337Y747065D02*
Y740865D01*
G01X1265537Y747065D02*
X1262337D01*
G01X1251860Y758865D02*
Y765065D01*
G01X1255344Y1666422D02*
X1255114Y1666060D01*
X1254808Y1665854D01*
X1254463Y1665802D01*
X1254156Y1665854D01*
X1253849Y1666112D01*
X1253658Y1666422D01*
X1253619Y1666732D01*
X1253696Y1667094D01*
X1253964Y1667352D01*
X1254233Y1667455D01*
X1254578D01*
G01X1254233D02*
X1254003Y1667610D01*
X1253811Y1667869D01*
X1253734Y1668179D01*
X1253811Y1668489D01*
X1254003Y1668747D01*
X1254348Y1668902D01*
X1254693Y1668850D01*
X1255038Y1668644D01*
G01X1261915Y1665802D02*
Y1668902D01*
X1263333Y1666680D01*
X1261417D01*
G01X1268323Y102060D02*
Y108260D01*
G01X1277945Y98030D02*
Y104230D01*
G01X1274745Y98030D02*
X1277945D01*
G01X1274745Y104230D02*
Y98030D01*
G01X1281085Y115125D02*
X1277885D01*
G01X1281085Y108925D02*
Y115125D01*
G01X1277885Y108925D02*
X1281085D01*
G01X1277885Y115125D02*
Y108925D01*
G01X1277945Y104230D02*
X1274745D01*
G01X1267916Y143523D02*
X1265654Y145785D01*
G01X1266972Y149413D02*
X1271356Y153797D01*
G01X1268556Y156867D02*
X1266294Y159129D01*
G01X1271356Y153797D02*
X1269094Y156059D01*
G01X1281173Y188787D02*
X1287373D01*
G01X1281173Y191987D02*
Y188787D01*
G01X1287373Y191987D02*
X1281173D01*
G01X1268264Y198222D02*
Y195022D01*
G01X1274464Y198222D02*
X1268264D01*
G01X1274464Y195022D02*
Y198222D01*
G01X1268264Y195022D02*
X1274464D01*
G01X1274758Y233606D02*
Y236806D01*
G01X1268558Y233606D02*
X1274758D01*
G01X1268558Y236806D02*
Y233606D01*
G01X1268493Y231062D02*
Y227862D01*
G01X1274693Y231062D02*
X1268493D01*
G01X1274693Y227862D02*
Y231062D01*
G01X1268493Y227862D02*
X1274693D01*
G01X1268493Y227062D02*
Y223862D01*
G01X1274693Y227062D02*
X1268493D01*
G01X1274693Y223862D02*
Y227062D01*
G01X1268493Y223862D02*
X1274693D01*
G01X1278691Y241014D02*
X1281891D01*
G01X1278691Y247214D02*
Y241014D01*
G01X1281891Y247214D02*
X1278691D01*
G01X1274758Y236806D02*
X1268558D01*
G01X1273404Y269532D02*
X1267404D01*
Y257532D01*
X1273404D01*
Y269532D01*
G01X1279845Y258051D02*
X1284445D01*
G01X1279845Y268251D02*
Y258051D01*
G01X1284445Y263151D02*
X1279845D01*
G01X1274601Y258025D02*
X1279201D01*
G01X1274601Y268225D02*
Y258025D01*
G01X1279201D02*
Y268225D01*
G01Y263125D02*
X1274601D01*
G01X1284445Y268251D02*
X1279845D01*
G01X1279201Y268225D02*
X1274601D01*
G01X1286147Y300212D02*
Y303312D01*
X1285227D01*
X1284920Y303157D01*
X1284690Y302795D01*
X1284613Y302382D01*
X1284690Y301969D01*
X1284882Y301659D01*
X1285227Y301504D01*
X1286147D01*
G01X1283047Y300832D02*
X1282855Y300522D01*
X1282625Y300315D01*
X1282357Y300212D01*
X1282050Y300315D01*
X1281820Y300522D01*
X1281590Y300832D01*
X1281513Y301245D01*
Y303312D01*
G01X1279908Y301504D02*
X1279640Y301865D01*
X1279410Y302072D01*
X1279103Y302175D01*
X1278835Y302072D01*
X1278643Y301865D01*
X1278490Y301555D01*
X1278452Y301194D01*
X1278490Y300884D01*
X1278643Y300574D01*
X1278873Y300315D01*
X1279142Y300212D01*
X1279448Y300315D01*
X1279717Y300625D01*
X1279870Y301090D01*
X1279908Y301607D01*
X1279832Y302279D01*
X1279717Y302640D01*
X1279525Y303002D01*
X1279257Y303260D01*
X1278988Y303312D01*
X1278720Y303209D01*
X1278528Y302950D01*
G01X1276923Y300832D02*
X1276693Y300470D01*
X1276387Y300264D01*
X1276042Y300212D01*
X1275735Y300264D01*
X1275428Y300522D01*
X1275237Y300832D01*
X1275198Y301142D01*
X1275275Y301504D01*
X1275543Y301762D01*
X1275812Y301865D01*
X1276157D01*
G01X1275812D02*
X1275582Y302020D01*
X1275390Y302279D01*
X1275313Y302589D01*
X1275390Y302899D01*
X1275582Y303157D01*
X1275927Y303312D01*
X1276272Y303260D01*
X1276617Y303054D01*
G01X1275657Y731885D02*
X1278857D01*
G01X1275657Y738085D02*
Y731885D01*
G01X1278857Y738085D02*
X1275657D01*
G01X1278857Y731885D02*
Y738085D01*
G01X1271657Y731965D02*
X1274857D01*
G01X1271657Y738165D02*
Y731965D01*
G01X1274857D02*
Y738165D01*
G01X1279197Y738865D02*
X1282397D01*
G01X1279197Y745065D02*
Y738865D01*
G01X1282397Y745065D02*
X1279197D01*
G01X1274857Y738165D02*
X1271657D01*
G01X1265537Y740865D02*
Y747065D01*
G01X1275857Y745165D02*
X1272657D01*
G01X1275857Y738965D02*
Y745165D01*
G01X1272657Y738965D02*
X1275857D01*
G01X1272657Y745165D02*
Y738965D01*
G01X1272598Y745991D02*
X1275798D01*
G01X1272598Y752191D02*
Y745991D01*
G01X1275798Y752191D02*
X1272598D01*
G01X1275798Y745991D02*
Y752191D01*
G01X1292864Y991220D02*
G03I-9950J0D01*
G01X1278580Y1302517D02*
Y1308717D01*
G01X1275380Y1302517D02*
X1278580D01*
G01X1275380Y1308717D02*
Y1302517D01*
G01X1278580Y1308717D02*
X1275380D01*
G01Y1310152D02*
X1278580D01*
G01X1275380Y1316352D02*
Y1310152D01*
G01X1278580Y1316352D02*
X1275380D01*
G01X1278580Y1310152D02*
Y1316352D01*
G01X1277456Y1350947D02*
Y1357147D01*
G01X1274256Y1350947D02*
X1277456D01*
G01X1274256Y1357147D02*
Y1350947D01*
G01X1280713D02*
X1283913D01*
G01X1280713Y1357147D02*
Y1350947D01*
G01X1273946D02*
Y1357147D01*
G01X1270746Y1350947D02*
X1273946D01*
G01X1270746Y1357147D02*
Y1350947D01*
G01X1277456Y1357147D02*
X1274256D01*
G01X1283913D02*
X1280713D01*
G01X1273946D02*
X1270746D01*
G01X1278592Y1358216D02*
X1281792D01*
G01X1278592Y1364416D02*
Y1358216D01*
G01X1281792Y1364416D02*
X1278592D01*
G01X1278851Y1667094D02*
X1278583Y1667455D01*
X1278353Y1667662D01*
X1278046Y1667765D01*
X1277778Y1667662D01*
X1277586Y1667455D01*
X1277433Y1667145D01*
X1277395Y1666784D01*
X1277433Y1666474D01*
X1277586Y1666164D01*
X1277816Y1665905D01*
X1278085Y1665802D01*
X1278391Y1665905D01*
X1278660Y1666215D01*
X1278813Y1666680D01*
X1278851Y1667197D01*
X1278775Y1667869D01*
X1278660Y1668230D01*
X1278468Y1668592D01*
X1278200Y1668850D01*
X1277931Y1668902D01*
X1277663Y1668799D01*
X1277471Y1668540D01*
G01X1271092Y1666267D02*
X1270862Y1666009D01*
X1270594Y1665854D01*
X1270249Y1665802D01*
X1269904Y1665905D01*
X1269636Y1666112D01*
X1269444Y1666474D01*
X1269406Y1666887D01*
X1269482Y1667300D01*
X1269674Y1667559D01*
X1269942Y1667765D01*
X1270211Y1667817D01*
X1270479Y1667765D01*
X1270824Y1667559D01*
X1270709Y1668902D01*
X1269674D01*
G01X1291422Y-23211D02*
Y-39811D01*
X1301022D01*
Y-23211D01*
X1291422D01*
G01Y-3211D02*
Y-19811D01*
X1301022D01*
Y-3211D01*
X1291422D01*
G01Y16789D02*
Y189D01*
X1301022D01*
Y16789D01*
X1291422D01*
G01X1296221Y98488D02*
X1299421D01*
G01X1296221Y104688D02*
Y98488D01*
G01X1293304Y101631D02*
Y107831D01*
G01X1290104Y101631D02*
X1293304D01*
G01X1290104Y107831D02*
Y101631D01*
G01X1281885Y110455D02*
X1285085D01*
G01X1281885Y116655D02*
Y110455D01*
G01X1285085Y116655D02*
X1281885D01*
G01X1285085Y110455D02*
Y116655D01*
G01X1286041Y110455D02*
X1289241D01*
G01X1286041Y116655D02*
Y110455D01*
G01X1289241Y116655D02*
X1286041D01*
G01X1289241Y110455D02*
Y116655D01*
G01X1290104Y110494D02*
X1293304D01*
G01X1290104Y116694D02*
Y110494D01*
G01X1293304Y116694D02*
X1290104D01*
G01X1293304Y110494D02*
Y116694D01*
G01X1297407Y116693D02*
X1294207D01*
G01X1297407Y110493D02*
Y116693D01*
G01X1294207Y110493D02*
X1297407D01*
G01X1294207Y116693D02*
Y110493D01*
G01X1299421Y104688D02*
X1296221D01*
G01X1293304Y107831D02*
X1290104D01*
G01X1287373Y188787D02*
Y191987D01*
G01X1306502Y254880D02*
X1298017Y246395D01*
G01D02*
X1302260Y242152D01*
G01X1297890Y247763D02*
X1305103Y254976D01*
G01X1294637Y251016D02*
X1297890Y247763D01*
G01X1285720Y240042D02*
Y246242D01*
G01D02*
X1282520D01*
G01D02*
Y240042D01*
G01D02*
X1285720D01*
G01X1281891Y241014D02*
Y247214D01*
G01X1284445Y258051D02*
Y268251D01*
G01X1301850Y258229D02*
X1294637Y251016D01*
G01X1300981Y258860D02*
X1297728Y262113D01*
G01X1293768Y251647D02*
X1300981Y258860D01*
G01X1290515Y254900D02*
X1293768Y251647D01*
G01X1297728Y262113D02*
X1290515Y254900D01*
G01X1294122Y258506D02*
X1297374Y255254D01*
G01X1297131Y262786D02*
X1293878Y266039D01*
G01X1289918Y255573D02*
X1297131Y262786D01*
G01X1286665Y258826D02*
X1289918Y255573D01*
G01X1293878Y266039D02*
X1286665Y258826D01*
G01X1290272Y262432D02*
X1293524Y259180D01*
G01X1289520Y266052D02*
Y272052D01*
X1286520D01*
Y266052D01*
X1289520D01*
G01X1301507Y281762D02*
Y284862D01*
X1300587D01*
X1300280Y284707D01*
X1300050Y284345D01*
X1299973Y283932D01*
X1300050Y283519D01*
X1300242Y283209D01*
X1300587Y283054D01*
X1301507D01*
G01X1298407Y282382D02*
X1298215Y282072D01*
X1297985Y281865D01*
X1297717Y281762D01*
X1297410Y281865D01*
X1297180Y282072D01*
X1296950Y282382D01*
X1296873Y282795D01*
Y284862D01*
G01X1295268Y283054D02*
X1295000Y283415D01*
X1294770Y283622D01*
X1294463Y283725D01*
X1294195Y283622D01*
X1294003Y283415D01*
X1293850Y283105D01*
X1293812Y282744D01*
X1293850Y282434D01*
X1294003Y282124D01*
X1294233Y281865D01*
X1294502Y281762D01*
X1294808Y281865D01*
X1295077Y282175D01*
X1295230Y282640D01*
X1295268Y283157D01*
X1295192Y283829D01*
X1295077Y284190D01*
X1294885Y284552D01*
X1294617Y284810D01*
X1294348Y284862D01*
X1294080Y284759D01*
X1293888Y284500D01*
G01X1292168Y284345D02*
X1291938Y284655D01*
X1291670Y284810D01*
X1291363Y284862D01*
X1290980Y284759D01*
X1290712Y284500D01*
X1290635Y284190D01*
X1290673Y283880D01*
X1290827Y283622D01*
X1291593Y283105D01*
X1291938Y282744D01*
X1292168Y282227D01*
X1292245Y281762D01*
X1290635D01*
G01X1289493Y274807D02*
Y278007D01*
G01X1283293Y274807D02*
X1289493D01*
G01X1283293Y278007D02*
Y274807D01*
G01X1289493Y278007D02*
X1283293D01*
G01X1294347Y723625D02*
X1297547D01*
G01X1294347Y729825D02*
Y723625D01*
G01X1297547Y729825D02*
X1294347D01*
G01X1297547Y723625D02*
Y729825D01*
G01Y736825D02*
X1294347D01*
G01X1297547Y730625D02*
Y736825D01*
G01X1294347Y730625D02*
X1297547D01*
G01X1294347Y736825D02*
Y730625D01*
G01X1290407Y725635D02*
X1293607D01*
G01X1290407Y731835D02*
Y725635D01*
G01X1293607Y731835D02*
X1290407D01*
G01X1293607Y725635D02*
Y731835D01*
G01X1282397Y738865D02*
Y745065D01*
G01X1293337Y747865D02*
X1296537D01*
G01X1293337Y754065D02*
Y747865D01*
G01X1296537Y754065D02*
X1293337D01*
G01X1296537Y747865D02*
Y754065D01*
G01X1291417Y745670D02*
X1288217D01*
G01X1291417Y739470D02*
Y745670D01*
G01X1288217Y739470D02*
X1291417D01*
G01X1288217Y745670D02*
Y739470D01*
G01X1283197Y740585D02*
X1286397D01*
G01X1283197Y746785D02*
Y740585D01*
G01X1286397Y746785D02*
X1283197D01*
G01X1286397Y740585D02*
Y746785D01*
G01X1292459Y1307498D02*
Y1319498D01*
G01X1286459Y1307498D02*
X1292459D01*
G01X1286459Y1319498D02*
Y1307498D01*
G01X1293722Y1307470D02*
X1299722D01*
G01X1293722Y1319470D02*
Y1307470D01*
G01X1292459Y1319498D02*
X1286459D01*
G01X1299722Y1319470D02*
X1293722D01*
G01X1295182Y1356144D02*
Y1344144D01*
G01X1301182Y1356144D02*
X1295182D01*
G01Y1344144D02*
X1301182D01*
G01X1283913Y1350947D02*
Y1357147D01*
G01X1296685Y1359387D02*
X1302685D01*
G01X1296685Y1371387D02*
Y1359387D01*
G01X1302685Y1371387D02*
X1296685D01*
G01X1281792Y1358216D02*
Y1364416D01*
G01X1360707Y1646650D02*
Y1654150D01*
X1358467D01*
X1357720Y1653775D01*
X1357160Y1652900D01*
X1356973Y1651900D01*
X1357160Y1650900D01*
X1357627Y1650150D01*
X1358467Y1649775D01*
X1360707D01*
G01X1353207Y1646650D02*
Y1654150D01*
X1350873D01*
X1350127Y1653775D01*
X1349660Y1653275D01*
X1349473Y1652275D01*
X1349660Y1651275D01*
X1350220Y1650650D01*
X1350873Y1650275D01*
X1353207D01*
G01X1350873D02*
X1349473Y1646650D01*
G01X1341973D02*
X1345707D01*
Y1654150D01*
X1341973D01*
G01X1343467Y1650525D02*
X1345707D01*
G01X1338300Y1647650D02*
X1337553Y1647025D01*
X1336713Y1646650D01*
X1335967D01*
X1335220Y1647025D01*
X1334660Y1647650D01*
X1334380Y1648525D01*
X1334567Y1649400D01*
X1335033Y1650150D01*
X1335873Y1650650D01*
X1336993Y1650900D01*
X1337647Y1651400D01*
X1337927Y1652275D01*
X1337740Y1653150D01*
X1337273Y1653775D01*
X1336620Y1654150D01*
X1335967D01*
X1335313Y1653900D01*
X1334753Y1653275D01*
G01X1330800Y1647650D02*
X1330053Y1647025D01*
X1329213Y1646650D01*
X1328467D01*
X1327720Y1647025D01*
X1327160Y1647650D01*
X1326880Y1648525D01*
X1327067Y1649400D01*
X1327533Y1650150D01*
X1328373Y1650650D01*
X1329493Y1650900D01*
X1330147Y1651400D01*
X1330427Y1652275D01*
X1330240Y1653150D01*
X1329773Y1653775D01*
X1329120Y1654150D01*
X1328467D01*
X1327813Y1653900D01*
X1327253Y1653275D01*
G01X1322553Y1649150D02*
X1320127D01*
G01X1315613Y1646650D02*
Y1654150D01*
X1312067D01*
G01X1313373Y1650525D02*
X1315613D01*
G01X1307460Y1654150D02*
X1305220D01*
G01X1306340D02*
Y1646650D01*
G01X1307460D02*
X1305220D01*
G01X1298840Y1654150D02*
Y1646650D01*
G01X1300987Y1654150D02*
X1296693D01*
G01X1379134Y1646023D02*
X1288977D01*
G01D02*
Y1781456D01*
G01X1286074Y1665802D02*
X1285997Y1666474D01*
X1285882Y1667042D01*
X1285729Y1667559D01*
X1285537Y1668127D01*
X1285230Y1668902D01*
X1286764D01*
G01X1293871Y1665802D02*
X1293603Y1665854D01*
X1293296Y1666009D01*
X1293104Y1666267D01*
X1293028Y1666629D01*
X1293104Y1666990D01*
X1293334Y1667300D01*
X1293679Y1667455D01*
X1294063D01*
X1294293Y1667559D01*
X1294484Y1667817D01*
X1294561Y1668179D01*
X1294446Y1668540D01*
X1294178Y1668799D01*
X1293871Y1668902D01*
X1293564Y1668799D01*
X1293296Y1668540D01*
X1293181Y1668179D01*
X1293258Y1667817D01*
X1293449Y1667559D01*
X1293679Y1667455D01*
X1294063D01*
X1294408Y1667300D01*
X1294638Y1666990D01*
X1294714Y1666629D01*
X1294638Y1666267D01*
X1294446Y1666009D01*
X1294139Y1665854D01*
X1293871Y1665802D01*
G01X1288977Y1781456D02*
X1379134D01*
G01X1312620Y-37617D02*
X1312310Y-37425D01*
X1312103Y-37195D01*
X1312000Y-36927D01*
X1312103Y-36620D01*
X1312310Y-36390D01*
X1312620Y-36160D01*
X1313033Y-36083D01*
X1315100D01*
G01X1312000Y-33750D02*
X1315100D01*
X1314480Y-34210D01*
G01X1312000D02*
Y-33290D01*
G01X1314583Y-31378D02*
X1314893Y-31148D01*
X1315048Y-30880D01*
X1315100Y-30573D01*
X1314997Y-30190D01*
X1314738Y-29922D01*
X1314428Y-29845D01*
X1314118Y-29883D01*
X1313860Y-30037D01*
X1313343Y-30803D01*
X1312982Y-31148D01*
X1312465Y-31378D01*
X1312000Y-31455D01*
Y-29845D01*
G01X1315100Y-27550D02*
X1314997Y-27857D01*
X1314738Y-28087D01*
X1314428Y-28240D01*
X1314015Y-28355D01*
X1313550Y-28393D01*
X1313085Y-28355D01*
X1312672Y-28240D01*
X1312362Y-28087D01*
X1312103Y-27857D01*
X1312000Y-27550D01*
X1312103Y-27243D01*
X1312362Y-27013D01*
X1312672Y-26860D01*
X1313085Y-26745D01*
X1313550Y-26707D01*
X1314015Y-26745D01*
X1314428Y-26860D01*
X1314738Y-27013D01*
X1314997Y-27243D01*
X1315100Y-27550D01*
G01X1312620Y-17117D02*
X1312310Y-16925D01*
X1312103Y-16695D01*
X1312000Y-16427D01*
X1312103Y-16120D01*
X1312310Y-15890D01*
X1312620Y-15660D01*
X1313033Y-15583D01*
X1315100D01*
G01X1312000Y-13250D02*
X1315100D01*
X1314480Y-13710D01*
G01X1312000D02*
Y-12790D01*
G01Y-10150D02*
X1315100D01*
X1314480Y-10610D01*
G01X1312000D02*
Y-9690D01*
G01X1312362Y-7702D02*
X1312103Y-7433D01*
X1312000Y-7127D01*
X1312103Y-6820D01*
X1312413Y-6552D01*
X1312878Y-6360D01*
X1313343Y-6283D01*
X1313912D01*
X1314377Y-6360D01*
X1314790Y-6552D01*
X1314997Y-6782D01*
X1315100Y-7050D01*
X1314997Y-7357D01*
X1314790Y-7587D01*
X1314480Y-7740D01*
X1314067Y-7817D01*
X1313705Y-7740D01*
X1313343Y-7548D01*
X1313137Y-7318D01*
X1313085Y-7050D01*
X1313188Y-6743D01*
X1313447Y-6513D01*
X1313912Y-6283D01*
G01X1312620Y4383D02*
X1312310Y4575D01*
X1312103Y4805D01*
X1312000Y5073D01*
X1312103Y5380D01*
X1312310Y5610D01*
X1312620Y5840D01*
X1313033Y5917D01*
X1315100D01*
G01X1312000Y8250D02*
X1312052Y8518D01*
X1312207Y8825D01*
X1312465Y9017D01*
X1312827Y9093D01*
X1313188Y9017D01*
X1313498Y8787D01*
X1313653Y8442D01*
Y8058D01*
X1313757Y7828D01*
X1314015Y7637D01*
X1314377Y7560D01*
X1314738Y7675D01*
X1314997Y7943D01*
X1315100Y8250D01*
X1314997Y8557D01*
X1314738Y8825D01*
X1314377Y8940D01*
X1314015Y8863D01*
X1313757Y8672D01*
X1313653Y8442D01*
Y8058D01*
X1313498Y7713D01*
X1313188Y7483D01*
X1312827Y7407D01*
X1312465Y7483D01*
X1312207Y7675D01*
X1312052Y7982D01*
X1312000Y8250D01*
G01X1314583Y10622D02*
X1314893Y10852D01*
X1315048Y11120D01*
X1315100Y11427D01*
X1314997Y11810D01*
X1314738Y12078D01*
X1314428Y12155D01*
X1314118Y12117D01*
X1313860Y11963D01*
X1313343Y11197D01*
X1312982Y10852D01*
X1312465Y10622D01*
X1312000Y10545D01*
Y12155D01*
G01X1306620Y97662D02*
Y100862D01*
G01X1300420Y97662D02*
X1306620D01*
G01X1300420Y100862D02*
Y97662D01*
G01X1306620Y100862D02*
X1300420D01*
G01X1299421Y98488D02*
Y104688D01*
G01X1304820Y112162D02*
X1301620D01*
G01X1304820Y105962D02*
Y112162D01*
G01X1301620Y105962D02*
X1304820D01*
G01X1301620Y112162D02*
Y105962D01*
G01X1311750Y133704D02*
X1308550D01*
G01X1311750Y127504D02*
Y133704D01*
G01X1308550Y127504D02*
X1311750D01*
G01X1308550Y133704D02*
Y127504D01*
G01X1310828Y126668D02*
X1307628D01*
G01X1310828Y120468D02*
Y126668D01*
G01X1307628Y120468D02*
X1310828D01*
G01X1307628Y126668D02*
Y120468D01*
G01X1315869Y126713D02*
X1312669D01*
G01Y120513D02*
X1315869D01*
G01X1312669Y126713D02*
Y120513D01*
G01X1298290Y125642D02*
X1301490D01*
G01X1298290Y131842D02*
Y125642D01*
G01X1301490Y131842D02*
X1298290D01*
G01X1301490Y125642D02*
Y131842D01*
G01X1305328Y131890D02*
X1302128D01*
G01X1305328Y125690D02*
Y131890D01*
G01X1302128Y125690D02*
X1305328D01*
G01X1302128Y131890D02*
Y125690D01*
G01X1311022Y175416D02*
X1317222D01*
G01X1311022Y178616D02*
Y175416D01*
G01X1317222Y178616D02*
X1311022D01*
G01X1314210Y191402D02*
X1320410D01*
G01X1314210Y194602D02*
Y191402D01*
G01X1320410Y194602D02*
X1314210D01*
G01X1310964Y225109D02*
X1315564D01*
G01X1310964Y235309D02*
Y225109D01*
G01X1315564Y230209D02*
X1310964D01*
G01X1305564Y225109D02*
X1310164D01*
G01X1305564Y235309D02*
Y225109D01*
G01X1310164D02*
Y235309D01*
G01Y230209D02*
X1305564D01*
G01X1311795Y249755D02*
X1303310Y241270D01*
G01X1316038Y245512D02*
X1311795Y249755D01*
G01X1307553Y237027D02*
X1316038Y245512D01*
G01X1303310Y241270D02*
X1307553Y237027D01*
G01X1302260Y242152D02*
X1310745Y250637D01*
G01X1315564Y235309D02*
X1310964D01*
G01X1310164D02*
X1305564D01*
G01X1310745Y250637D02*
X1306502Y254880D01*
G01X1305103Y254976D02*
X1301850Y258229D01*
G01X1298244Y254622D02*
X1301496Y251370D01*
G01X1311607Y732975D02*
Y729775D01*
G01X1317807Y732975D02*
X1311607D01*
G01Y729775D02*
X1317807D01*
G01X1301917Y735795D02*
Y741995D01*
G01X1298717Y735795D02*
X1301917D01*
G01X1298717Y741995D02*
Y735795D01*
G01X1310447Y754395D02*
X1307247D01*
G01X1310447Y748195D02*
Y754395D01*
G01X1307247Y748195D02*
X1310447D01*
G01X1307247Y754395D02*
Y748195D01*
G01X1306877Y754395D02*
X1303677D01*
G01X1306877Y748195D02*
Y754395D01*
G01X1303677Y748195D02*
X1306877D01*
G01X1303677Y754395D02*
Y748195D01*
G01X1311997Y740695D02*
X1315197D01*
G01X1311997Y746895D02*
Y740695D01*
G01X1315197Y746895D02*
X1311997D01*
G01X1301917Y741995D02*
X1298717D01*
G01X1299887Y748195D02*
X1303087D01*
G01X1299887Y754395D02*
Y748195D01*
G01X1303087Y754395D02*
X1299887D01*
G01X1303087Y748195D02*
Y754395D01*
G01X1309529Y1286512D02*
X1315529D01*
G01X1309529Y1298512D02*
Y1286512D01*
G01X1315529Y1298512D02*
X1309529D01*
G01X1299722Y1307470D02*
Y1319470D01*
G01X1302161Y1311452D02*
X1305361D01*
G01X1302161Y1317652D02*
Y1311452D01*
G01X1305361Y1317652D02*
X1302161D01*
G01X1305361Y1311452D02*
Y1317652D01*
G01X1312841Y1328149D02*
X1316041D01*
G01X1312841Y1334349D02*
Y1328149D01*
G01X1316041Y1334349D02*
X1312841D01*
G01X1310720Y1335418D02*
X1313920D01*
G01X1310720Y1341618D02*
Y1335418D01*
G01X1313920D02*
Y1341618D01*
G01X1303588Y1356144D02*
Y1344144D01*
G01X1309588Y1356144D02*
X1303588D01*
G01X1309588Y1344144D02*
Y1356144D01*
G01X1303588Y1344144D02*
X1309588D01*
G01X1301182D02*
Y1356144D01*
G01X1313920Y1341618D02*
X1310720D01*
G01X1302685Y1359387D02*
Y1371387D01*
G01X1312205Y1658020D02*
Y1646023D01*
G01Y1667550D02*
Y1662750D01*
G01X1307192Y1665802D02*
Y1668902D01*
X1307652Y1668282D01*
G01Y1665802D02*
X1306732D01*
G01X1315794Y1668385D02*
X1315564Y1668695D01*
X1315296Y1668850D01*
X1314989Y1668902D01*
X1314606Y1668799D01*
X1314338Y1668540D01*
X1314261Y1668230D01*
X1314299Y1667920D01*
X1314453Y1667662D01*
X1315219Y1667145D01*
X1315564Y1666784D01*
X1315794Y1666267D01*
X1315871Y1665802D01*
X1314261D01*
G01X1301856Y1683193D02*
Y1680093D01*
X1300322D01*
G01X1302086Y1675369D02*
Y1678469D01*
X1301089Y1675886D01*
X1300092Y1678469D01*
Y1675369D01*
G01X1301971Y1670645D02*
Y1673745D01*
X1300207Y1670645D01*
Y1673745D01*
G01X1301549Y1697367D02*
X1300629D01*
G01X1301089D02*
Y1694267D01*
G01X1301549D02*
X1300629D01*
G01X1301856Y1690162D02*
X1301664Y1689852D01*
X1301434Y1689645D01*
X1301166Y1689542D01*
X1300859Y1689645D01*
X1300629Y1689852D01*
X1300399Y1690162D01*
X1300322Y1690575D01*
Y1692642D01*
G01X1301932Y1684818D02*
Y1687918D01*
G01X1300476D02*
X1301932Y1686006D01*
G01X1300246Y1684818D02*
X1301281Y1686885D01*
G01X1301888Y1698562D02*
Y1701662D01*
G01X1300278D02*
Y1698562D01*
G01Y1700112D02*
X1301888D01*
G01X1300322Y1713164D02*
X1301856D01*
Y1716264D01*
X1300322D01*
G01X1300936Y1714766D02*
X1301856D01*
G01X1301817Y1708440D02*
Y1711540D01*
X1300361D01*
G01X1300897Y1710042D02*
X1301817D01*
G01X1300753Y1704912D02*
X1299986D01*
Y1703982D01*
X1300216Y1703672D01*
X1300485Y1703465D01*
X1300868Y1703362D01*
X1301251Y1703465D01*
X1301520Y1703672D01*
X1301750Y1703982D01*
X1301903Y1704344D01*
X1301980Y1704757D01*
Y1705119D01*
X1301903Y1705429D01*
X1301750Y1705790D01*
X1301520Y1706100D01*
X1301290Y1706307D01*
X1300983Y1706462D01*
X1300715D01*
X1300408Y1706359D01*
X1300178Y1706152D01*
G01X1300782Y1728991D02*
X1300629Y1729146D01*
X1300514Y1729405D01*
X1300437Y1729766D01*
X1300514Y1730076D01*
X1300667Y1730283D01*
X1300936Y1730438D01*
X1301971D01*
Y1727338D01*
X1300706D01*
X1300437Y1727545D01*
X1300284Y1727855D01*
X1300207Y1728216D01*
X1300284Y1728578D01*
X1300514Y1728888D01*
X1300782Y1728991D01*
X1301971D01*
G01X1300246Y1725455D02*
X1300476Y1725610D01*
X1300744Y1725713D01*
X1301051D01*
X1301396Y1725558D01*
X1301664Y1725300D01*
X1301856Y1724990D01*
X1302009Y1724473D01*
X1302047Y1724008D01*
X1301971Y1723543D01*
X1301856Y1723233D01*
X1301626Y1722923D01*
X1301357Y1722716D01*
X1301089Y1722613D01*
X1300821D01*
X1300552Y1722716D01*
X1300322Y1722871D01*
X1300131Y1723078D01*
G01X1301932Y1717889D02*
Y1720989D01*
X1301166D01*
X1300859Y1720834D01*
X1300629Y1720627D01*
X1300437Y1720317D01*
X1300284Y1719956D01*
X1300246Y1719439D01*
X1300284Y1718922D01*
X1300437Y1718561D01*
X1300629Y1718251D01*
X1300859Y1718044D01*
X1301166Y1717889D01*
X1301932D01*
G01X1312205Y1781456D02*
Y1738490D01*
G01X1301841Y1732562D02*
X1300883Y1735662D01*
X1299925Y1732562D01*
G01X1300270Y1733647D02*
X1301496D01*
G01X1318620Y-37617D02*
X1318310Y-37425D01*
X1318103Y-37195D01*
X1318000Y-36927D01*
X1318103Y-36620D01*
X1318310Y-36390D01*
X1318620Y-36160D01*
X1319033Y-36083D01*
X1321100D01*
G01X1318000Y-33750D02*
X1321100D01*
X1320480Y-34210D01*
G01X1318000D02*
Y-33290D01*
G01Y-30650D02*
X1321100D01*
X1320480Y-31110D01*
G01X1318000D02*
Y-30190D01*
G01Y-27090D02*
X1321100D01*
X1318878Y-28508D01*
Y-26592D01*
G01X1318620Y-17117D02*
X1318310Y-16925D01*
X1318103Y-16695D01*
X1318000Y-16427D01*
X1318103Y-16120D01*
X1318310Y-15890D01*
X1318620Y-15660D01*
X1319033Y-15583D01*
X1321100D01*
G01X1318000Y-13250D02*
X1321100D01*
X1320480Y-13710D01*
G01X1318000D02*
Y-12790D01*
G01Y-10150D02*
X1321100D01*
X1320480Y-10610D01*
G01X1318000D02*
Y-9690D01*
G01X1318465Y-7893D02*
X1318207Y-7663D01*
X1318052Y-7395D01*
X1318000Y-7050D01*
X1318103Y-6705D01*
X1318310Y-6437D01*
X1318672Y-6245D01*
X1319085Y-6207D01*
X1319498Y-6283D01*
X1319757Y-6475D01*
X1319963Y-6743D01*
X1320015Y-7012D01*
X1319963Y-7280D01*
X1319757Y-7625D01*
X1321100Y-7510D01*
Y-6475D01*
G01X1318320Y4283D02*
X1318010Y4475D01*
X1317803Y4705D01*
X1317700Y4973D01*
X1317803Y5280D01*
X1318010Y5510D01*
X1318320Y5740D01*
X1318733Y5817D01*
X1320800D01*
G01X1317700Y8073D02*
X1318372Y8150D01*
X1318940Y8265D01*
X1319457Y8418D01*
X1320025Y8610D01*
X1320800Y8917D01*
Y7383D01*
G01Y11250D02*
X1320697Y10943D01*
X1320438Y10713D01*
X1320128Y10560D01*
X1319715Y10445D01*
X1319250Y10407D01*
X1318785Y10445D01*
X1318372Y10560D01*
X1318062Y10713D01*
X1317803Y10943D01*
X1317700Y11250D01*
X1317803Y11557D01*
X1318062Y11787D01*
X1318372Y11940D01*
X1318785Y12055D01*
X1319250Y12093D01*
X1319715Y12055D01*
X1320128Y11940D01*
X1320438Y11787D01*
X1320697Y11557D01*
X1320800Y11250D01*
G01X1330546Y135880D02*
X1327346D01*
G01Y129680D02*
X1330546D01*
G01X1327346Y135880D02*
Y129680D01*
G01X1320888Y126702D02*
X1317688D01*
G01X1320888Y120502D02*
Y126702D01*
G01X1317688Y120502D02*
X1320888D01*
G01X1317688Y126702D02*
Y120502D01*
G01X1329028Y127877D02*
X1325828D01*
G01X1329028Y121677D02*
Y127877D01*
G01X1325828Y121677D02*
X1329028D01*
G01X1325828Y127877D02*
Y121677D01*
G01X1315869Y120513D02*
Y126713D01*
G01X1319491Y133703D02*
X1316291D01*
G01X1319491Y127503D02*
Y133703D01*
G01X1316291Y127503D02*
X1319491D01*
G01X1316291Y133703D02*
Y127503D01*
G01X1325093Y133830D02*
X1321893D01*
G01X1325093Y127630D02*
Y133830D01*
G01X1321893Y127630D02*
X1325093D01*
G01X1321893Y133830D02*
Y127630D01*
G01X1326550Y165872D02*
Y169072D01*
G01X1320350Y165872D02*
X1326550D01*
G01X1320350Y169072D02*
Y165872D01*
G01X1317222Y175416D02*
Y178616D01*
G01X1320901Y181499D02*
X1324101D01*
G01X1320901Y187699D02*
Y181499D01*
G01X1324101D02*
Y187699D01*
G01X1326620Y169677D02*
Y172877D01*
G01X1320420Y169677D02*
X1326620D01*
G01X1320420Y172877D02*
Y169677D01*
G01X1326620Y172877D02*
X1320420D01*
G01X1326550Y169072D02*
X1320350D01*
G01X1326420Y174621D02*
X1329620D01*
G01X1326420Y180821D02*
Y174621D01*
G01X1329620Y180821D02*
X1326420D01*
G01X1329620Y174621D02*
Y180821D01*
G01X1324077Y180776D02*
X1320877D01*
G01X1324077Y174576D02*
Y180776D01*
G01X1320877Y174576D02*
X1324077D01*
G01X1320877Y180776D02*
Y174576D01*
G01X1329173Y196423D02*
X1332373D01*
G01X1329173Y202623D02*
Y196423D01*
G01X1324101Y187699D02*
X1320901D01*
G01X1324122Y194570D02*
X1320922D01*
G01X1324122Y188370D02*
Y194570D01*
G01X1320922Y188370D02*
X1324122D01*
G01X1320922Y194570D02*
Y188370D01*
G01X1320535Y196488D02*
Y199688D01*
G01X1314335Y196488D02*
X1320535D01*
G01X1314335Y199688D02*
Y196488D01*
G01X1320535Y199688D02*
X1314335D01*
G01X1320410Y191402D02*
Y194602D01*
G01X1320535Y200541D02*
Y203741D01*
G01X1314335Y200541D02*
X1320535D01*
G01X1314335Y203741D02*
Y200541D01*
G01X1332373Y202623D02*
X1329173D01*
G01X1320535Y203741D02*
X1314335D01*
G01X1329200Y203300D02*
X1335400D01*
Y206500D01*
X1329200D01*
Y203300D01*
G01X1321596Y225162D02*
X1326196D01*
G01X1321596Y235362D02*
Y225162D01*
G01X1326196D02*
Y235362D01*
G01Y230262D02*
X1321596D01*
G01X1315564Y225109D02*
Y235309D01*
G01X1316327Y225079D02*
X1320927D01*
G01X1316327Y235279D02*
Y225079D01*
G01X1320927D02*
Y235279D01*
G01Y230179D02*
X1316327D01*
G01X1326196Y235362D02*
X1321596D01*
G01X1320927Y235279D02*
X1316327D01*
G01X1329348Y544247D02*
Y541047D01*
G01D02*
X1331340D01*
G01X1326198Y544247D02*
Y542852D01*
G01X1327270Y541047D02*
X1331340D01*
G01X1329271Y535721D02*
X1335471D01*
G01X1329271Y538921D02*
Y535721D01*
G01X1329890Y538921D02*
X1329271D01*
G01X1326121Y535721D02*
X1332321D01*
G01X1326121Y536992D02*
Y535721D01*
G01X1329890Y538921D02*
X1327270D01*
G01X1335548Y544247D02*
X1329348D01*
G01X1332398D02*
X1326198D01*
G01X1323416Y730769D02*
X1320216D01*
G01X1323416Y724569D02*
Y730769D01*
G01X1320216Y724569D02*
X1323416D01*
G01X1320216Y730769D02*
Y724569D01*
G01X1317807Y729775D02*
Y732975D01*
G01X1321683Y739347D02*
Y736147D01*
G01X1327883D02*
Y739347D01*
G01X1321683Y736147D02*
X1327883D01*
G01X1328728Y737042D02*
X1331928D01*
G01X1328728Y743242D02*
Y737042D01*
G01X1315967Y740705D02*
X1319167D01*
G01X1315967Y746905D02*
Y740705D01*
G01X1319167Y746905D02*
X1315967D01*
G01X1319167Y740705D02*
Y746905D01*
G01X1321632Y754395D02*
X1318432D01*
G01X1321632Y748195D02*
Y754395D01*
G01X1318432Y748195D02*
X1321632D01*
G01X1318432Y754395D02*
Y748195D01*
G01X1315197Y740695D02*
Y746895D01*
G01X1317907Y754395D02*
X1314707D01*
G01X1317907Y748195D02*
Y754395D01*
G01X1314707Y748195D02*
X1317907D01*
G01X1314707Y754395D02*
Y748195D01*
G01X1327883Y739347D02*
X1321683D01*
G01X1327883Y740107D02*
Y743307D01*
G01X1321683Y740107D02*
X1327883D01*
G01X1321683Y743307D02*
Y740107D01*
G01X1327883Y743307D02*
X1321683D01*
G01X1329288Y747909D02*
X1332488D01*
G01X1329288Y754109D02*
Y747909D01*
G01X1332488Y754109D02*
X1329288D01*
G01X1331928Y743242D02*
X1328728D01*
G01X1336190Y811121D02*
G03I-9950J0D01*
G01X1342155Y1171318D02*
G03I-9950J0D01*
G01X1324971Y1276040D02*
X1327211D01*
G01X1325998Y1274415D02*
Y1277665D01*
G01X1315529Y1286512D02*
Y1298512D01*
G01X1317436Y1282208D02*
X1335152D01*
G01X1317436Y1317904D02*
Y1282208D01*
G01X1327310Y1333346D02*
Y1321346D01*
G01D02*
X1333310D01*
G01X1320420Y1319829D02*
Y1322255D01*
G01X1335152Y1317904D02*
X1317436D01*
G01X1333310Y1333346D02*
X1327310D01*
G01X1328813Y1336589D02*
X1334813D01*
G01X1328813Y1348589D02*
Y1336589D01*
G01X1316041Y1328149D02*
Y1334349D01*
G01X1334813Y1348589D02*
X1328813D01*
G01X1323783Y1666422D02*
X1323553Y1666060D01*
X1323247Y1665854D01*
X1322902Y1665802D01*
X1322595Y1665854D01*
X1322288Y1666112D01*
X1322097Y1666422D01*
X1322058Y1666732D01*
X1322135Y1667094D01*
X1322403Y1667352D01*
X1322672Y1667455D01*
X1323017D01*
G01X1322672D02*
X1322442Y1667610D01*
X1322250Y1667869D01*
X1322173Y1668179D01*
X1322250Y1668489D01*
X1322442Y1668747D01*
X1322787Y1668902D01*
X1323132Y1668850D01*
X1323477Y1668644D01*
G01X1330354Y1665802D02*
Y1668902D01*
X1331772Y1666680D01*
X1329856D01*
G01X1340621Y-39811D02*
Y-23211D01*
X1331021D01*
Y-39811D01*
X1340621D01*
G01Y-19811D02*
Y-3211D01*
X1331021D01*
Y-19811D01*
X1340621D01*
G01Y189D02*
Y16789D01*
X1331021D01*
Y189D01*
X1340621D01*
G01X1340491Y122218D02*
Y119018D01*
G01X1346691D02*
Y122218D01*
G01X1340491Y119018D02*
X1346691D01*
G01Y123118D02*
Y126318D01*
G01X1340491Y123118D02*
X1346691D01*
G01X1340491Y126318D02*
Y123118D01*
G01X1346691Y126318D02*
X1340491D01*
G01X1330546Y129680D02*
Y135880D01*
G01X1334486Y130807D02*
X1331286D01*
G01X1334486Y124607D02*
Y130807D01*
G01X1331286Y124607D02*
X1334486D01*
G01X1331286Y130807D02*
Y124607D01*
G01X1338530Y128807D02*
X1335330D01*
G01X1338530Y122607D02*
Y128807D01*
G01X1335330Y122607D02*
X1338530D01*
G01X1335330Y128807D02*
Y122607D01*
G01X1346691Y122218D02*
X1340491D01*
G01X1345004Y144832D02*
X1348204D01*
G01X1345004Y151032D02*
Y144832D01*
G01X1348204Y151032D02*
X1345004D01*
G01X1340925Y144832D02*
X1344125D01*
G01X1340925Y151032D02*
Y144832D01*
G01X1344125Y151032D02*
X1340925D01*
G01X1344125Y144832D02*
Y151032D01*
G01X1332509Y180662D02*
Y177462D01*
G01X1338709Y180662D02*
X1332509D01*
G01X1338709Y177462D02*
Y180662D01*
G01X1332509Y177462D02*
X1338709D01*
G01X1332509Y184668D02*
Y181468D01*
G01X1338709Y184668D02*
X1332509D01*
G01X1338709Y181468D02*
Y184668D01*
G01X1332509Y181468D02*
X1338709D01*
G01X1338562Y174498D02*
X1340163Y171727D01*
G01X1343931Y177599D02*
X1338562Y174498D01*
G01X1345532Y174828D02*
X1343931Y177599D01*
G01X1340163Y171727D02*
X1345532Y174828D01*
G01X1338986Y197130D02*
Y193930D01*
G01X1345186Y197130D02*
X1338986D01*
G01X1345186Y193930D02*
Y197130D01*
G01X1338986Y193930D02*
X1345186D01*
G01X1336414Y196423D02*
Y202623D01*
G01X1333214Y196423D02*
X1336414D01*
G01X1333214Y202623D02*
Y196423D01*
G01X1332373D02*
Y202623D01*
G01X1332635Y188659D02*
Y185459D01*
G01X1338835Y188659D02*
X1332635D01*
G01X1338835Y185459D02*
Y188659D01*
G01X1332635Y185459D02*
X1338835D01*
G01X1332597Y192609D02*
Y189409D01*
G01X1338797Y192609D02*
X1332597D01*
G01X1338797Y189409D02*
Y192609D01*
G01X1332597Y189409D02*
X1338797D01*
G01X1338937Y201134D02*
Y197934D01*
G01X1345137Y201134D02*
X1338937D01*
G01X1345137Y197934D02*
Y201134D01*
G01X1338937Y197934D02*
X1345137D01*
G01X1336414Y202623D02*
X1333214D01*
G01X1341412Y201943D02*
X1344612D01*
G01X1341412Y208143D02*
Y201943D01*
G01X1344612Y208143D02*
X1341412D01*
G01X1344612Y201943D02*
Y208143D01*
G01X1346641Y202421D02*
X1349841D01*
G01X1346641Y208621D02*
Y202421D01*
G01X1349841Y208621D02*
X1346641D01*
G01X1336720Y213619D02*
X1333520D01*
G01X1336720Y207419D02*
Y213619D01*
G01X1333520Y207419D02*
X1336720D01*
G01X1333520Y213619D02*
Y207419D01*
G01X1337534Y213839D02*
Y210639D01*
G01D02*
X1343734D01*
G01D02*
Y213212D01*
G01X1341850Y213839D02*
X1337534D01*
G01X1333760Y541047D02*
X1335548D01*
G01D02*
Y541782D01*
G01X1332398Y542292D02*
Y544247D01*
G01X1335471Y538921D02*
X1331600D01*
G01X1335471Y535721D02*
Y536452D01*
G01Y538142D02*
Y538921D01*
G01X1332321Y535721D02*
Y538921D01*
G01D02*
X1331600D01*
G01X1335548Y543362D02*
Y544247D01*
G01X1332698Y737052D02*
X1335898D01*
G01X1332698Y743252D02*
Y737052D01*
G01X1335898D02*
Y743252D01*
G01X1331928Y737042D02*
Y743242D01*
G01X1340095Y753901D02*
X1336895D01*
G01X1340095Y747701D02*
Y753901D01*
G01X1336895Y747701D02*
X1340095D01*
G01X1336895Y753901D02*
Y747701D01*
G01X1335898Y743252D02*
X1332698D01*
G01X1336241Y754109D02*
X1333041D01*
G01X1336241Y747909D02*
Y754109D01*
G01X1333041Y747909D02*
X1336241D01*
G01X1333041Y754109D02*
Y747909D01*
G01X1332488D02*
Y754109D01*
G01X1343059Y1286512D02*
Y1298512D01*
G01X1337059Y1286512D02*
X1343059D01*
G01X1337059Y1298512D02*
Y1286512D01*
G01X1335152Y1282208D02*
Y1317904D01*
G01X1343059Y1298512D02*
X1337059D01*
G01X1333310Y1321346D02*
Y1333346D01*
G01X1335716D02*
Y1321346D01*
G01X1341716D02*
Y1333346D01*
G01X1335716Y1321346D02*
X1341716D01*
G01X1342932Y1320831D02*
X1346132D01*
G01X1342932Y1327031D02*
Y1320831D01*
G01X1346132D02*
Y1327031D01*
G01X1334813Y1336589D02*
Y1348589D01*
G01X1341716Y1333346D02*
X1335716D01*
G01X1346132Y1327031D02*
X1342932D01*
G01X1345627Y1381455D02*
Y1413255D01*
G01X1331827Y1381455D02*
X1345627D01*
G01X1331827Y1413255D02*
Y1381455D01*
G01X1345627Y1413255D02*
X1331827D01*
G01X1352887Y1559367D02*
Y1562467D01*
X1351890Y1559884D01*
X1350893Y1562467D01*
Y1559367D01*
G01X1348023D02*
X1349557D01*
Y1562467D01*
X1348023D01*
G01X1348637Y1560969D02*
X1349557D01*
G01X1345690Y1559367D02*
Y1562467D01*
X1346150Y1561847D01*
G01Y1559367D02*
X1345230D01*
G01X1342590D02*
Y1562467D01*
X1343050Y1561847D01*
G01Y1559367D02*
X1342130D01*
G01X1347290Y1667094D02*
X1347022Y1667455D01*
X1346792Y1667662D01*
X1346485Y1667765D01*
X1346217Y1667662D01*
X1346025Y1667455D01*
X1345872Y1667145D01*
X1345834Y1666784D01*
X1345872Y1666474D01*
X1346025Y1666164D01*
X1346255Y1665905D01*
X1346524Y1665802D01*
X1346830Y1665905D01*
X1347099Y1666215D01*
X1347252Y1666680D01*
X1347290Y1667197D01*
X1347214Y1667869D01*
X1347099Y1668230D01*
X1346907Y1668592D01*
X1346639Y1668850D01*
X1346370Y1668902D01*
X1346102Y1668799D01*
X1345910Y1668540D01*
G01X1339531Y1666267D02*
X1339301Y1666009D01*
X1339033Y1665854D01*
X1338688Y1665802D01*
X1338343Y1665905D01*
X1338075Y1666112D01*
X1337883Y1666474D01*
X1337845Y1666887D01*
X1337921Y1667300D01*
X1338113Y1667559D01*
X1338381Y1667765D01*
X1338650Y1667817D01*
X1338918Y1667765D01*
X1339263Y1667559D01*
X1339148Y1668902D01*
X1338113D01*
G01X1353692Y119018D02*
Y122218D01*
G01X1347492Y119018D02*
X1353692D01*
G01X1347492Y122218D02*
Y119018D01*
G01X1355450Y135572D02*
Y141772D01*
G01X1352250D02*
Y135572D01*
G01D02*
X1355450D01*
G01X1360662Y122523D02*
Y125723D01*
G01X1354462Y122523D02*
X1360662D01*
G01X1354462Y125723D02*
Y122523D01*
G01X1360662Y125723D02*
X1354462D01*
G01X1361062D02*
Y122523D01*
G01X1367262Y125723D02*
X1361062D01*
G01Y122523D02*
X1367262D01*
G01X1361062Y129885D02*
Y126685D01*
G01X1367262Y129885D02*
X1361062D01*
G01Y126685D02*
X1367262D01*
G01X1354462Y129885D02*
Y126685D01*
G01X1360662Y129885D02*
X1354462D01*
G01X1360662Y126685D02*
Y129885D01*
G01X1354462Y126685D02*
X1360662D01*
G01X1353692Y122218D02*
X1347492D01*
G01Y126318D02*
Y123118D01*
G01X1353692Y126318D02*
X1347492D01*
G01X1353692Y123118D02*
Y126318D01*
G01X1347492Y123118D02*
X1353692D01*
G01X1348204Y144832D02*
Y151032D01*
G01X1355450Y141772D02*
X1352250D01*
G01X1360009Y214519D02*
X1364609D01*
G01X1360009Y209419D02*
X1364609D01*
G01X1360009Y218952D02*
Y209419D01*
G01X1349841Y202421D02*
Y208621D01*
G01X1364609Y219619D02*
X1360930D01*
G01X1355458Y1273029D02*
Y1285029D01*
G01X1349458Y1273029D02*
X1355458D01*
G01X1349458Y1285029D02*
Y1273029D01*
G01X1357858D02*
X1363858D01*
G01X1357858Y1285029D02*
Y1273029D01*
G01X1355458Y1285029D02*
X1349458D01*
G01X1363858D02*
X1357858D01*
G01X1359174Y1319543D02*
Y1307543D01*
G01X1365174Y1319543D02*
X1359174D01*
G01Y1307543D02*
X1365174D01*
G01X1366941Y1334996D02*
X1360941D01*
Y1322996D01*
X1366941D01*
Y1334996D01*
G01X1346969Y1314823D02*
X1350169D01*
G01X1346969Y1321023D02*
Y1314823D01*
G01X1350169Y1321023D02*
X1346969D01*
G01X1350169Y1314823D02*
Y1321023D01*
G01X1354513Y1665802D02*
X1354436Y1666474D01*
X1354321Y1667042D01*
X1354168Y1667559D01*
X1353976Y1668127D01*
X1353669Y1668902D01*
X1355203D01*
G01X1362310Y1665802D02*
X1362042Y1665854D01*
X1361735Y1666009D01*
X1361543Y1666267D01*
X1361467Y1666629D01*
X1361543Y1666990D01*
X1361773Y1667300D01*
X1362118Y1667455D01*
X1362502D01*
X1362732Y1667559D01*
X1362923Y1667817D01*
X1363000Y1668179D01*
X1362885Y1668540D01*
X1362617Y1668799D01*
X1362310Y1668902D01*
X1362003Y1668799D01*
X1361735Y1668540D01*
X1361620Y1668179D01*
X1361697Y1667817D01*
X1361888Y1667559D01*
X1362118Y1667455D01*
X1362502D01*
X1362847Y1667300D01*
X1363077Y1666990D01*
X1363153Y1666629D01*
X1363077Y1666267D01*
X1362885Y1666009D01*
X1362578Y1665854D01*
X1362310Y1665802D01*
G01X1367262Y122523D02*
Y125723D01*
G01Y126685D02*
Y129885D01*
G01X1376212Y220314D02*
Y208314D01*
G01D02*
X1382212D01*
G01X1370811Y214552D02*
X1375411D01*
G01Y209452D02*
Y219652D01*
G01X1370811Y209452D02*
X1375411D01*
G01X1370811Y219652D02*
Y209452D01*
G01X1364609Y209419D02*
Y219619D01*
G01X1365411Y214504D02*
X1370011D01*
G01Y209404D02*
Y219604D01*
G01X1365411Y209404D02*
X1370011D01*
G01X1365411Y219604D02*
Y209404D01*
G01X1382212Y220314D02*
X1376212D01*
G01X1375411Y219652D02*
X1370811D01*
G01X1370011Y219604D02*
X1365411D01*
G01X1375373Y832541D02*
Y837141D01*
G01X1370273D02*
Y832541D01*
G01D02*
X1380473D01*
G01X1375373Y826120D02*
Y830720D01*
G01X1370273D02*
Y826120D01*
G01X1380473Y830720D02*
X1370273D01*
G01Y826120D02*
X1380473D01*
G01Y837141D02*
X1370273D01*
G01X1373667Y1154519D02*
X1385667D01*
G01X1373667Y1160519D02*
Y1154519D01*
G01X1385667Y1160519D02*
X1373667D01*
G01Y1162569D02*
X1385667D01*
G01X1373667Y1168569D02*
Y1162569D01*
G01X1385667Y1168569D02*
X1373667D01*
G01X1363858Y1273029D02*
Y1285029D01*
G01X1376739Y1273029D02*
Y1285029D01*
G01X1370739Y1273029D02*
X1376739D01*
G01X1370739Y1285029D02*
Y1273029D01*
G01X1378663Y1269030D02*
X1396379D01*
G01X1378663Y1304726D02*
Y1269030D01*
G01X1376739Y1285029D02*
X1370739D01*
G01X1365820Y1276962D02*
X1369020D01*
G01X1365820Y1283162D02*
Y1276962D01*
G01X1369020Y1283162D02*
X1365820D01*
G01X1369020Y1276962D02*
Y1283162D01*
G01X1381720Y1306979D02*
Y1309405D01*
G01X1396379Y1304726D02*
X1378663D01*
G01X1365174Y1307543D02*
Y1319543D01*
G01X1367610D02*
Y1307543D01*
G01X1373610Y1319543D02*
X1367610D01*
G01X1373610Y1307543D02*
Y1319543D01*
G01X1367610Y1307543D02*
X1373610D01*
G01X1375478Y1331733D02*
Y1328533D01*
G01D02*
X1381678D01*
G01Y1331733D02*
X1375478D01*
G01X1374126Y1404154D02*
Y1408754D01*
G01X1369026D02*
Y1404154D01*
G01X1379226D02*
Y1408754D01*
G01X1369026Y1404154D02*
X1379226D01*
G01X1368866Y1403934D02*
Y1400734D01*
G01X1375066Y1403934D02*
X1368866D01*
G01X1375066Y1400734D02*
Y1403934D01*
G01X1368866Y1400734D02*
X1375066D01*
G01X1379226Y1408754D02*
X1369026D01*
G01X1367950Y1418091D02*
Y1414891D01*
G01X1374150Y1418091D02*
X1367950D01*
G01X1374150Y1414891D02*
Y1418091D01*
G01X1367950Y1414891D02*
X1374150D01*
G01X1367950Y1414391D02*
Y1411191D01*
G01X1374150Y1414391D02*
X1367950D01*
G01X1374150Y1411191D02*
Y1414391D01*
G01X1367950Y1411191D02*
X1374150D01*
G01X1379134Y1781456D02*
Y1646023D01*
G01X1382212Y208314D02*
Y220314D01*
G01X1383212D02*
Y208314D01*
G01X1389212D02*
Y220314D01*
G01X1383212Y208314D02*
X1389212D01*
G01Y220314D02*
X1383212D01*
G01X1390350Y227852D02*
Y232452D01*
G01X1394850Y227852D02*
Y232452D01*
G01X1384850Y227852D02*
Y232452D01*
G01X1394850D02*
X1384850D01*
G01X1394850Y232352D02*
Y232452D01*
G01X1384850Y227852D02*
X1394850D01*
G01X1389350D02*
Y232452D01*
G01X1395037Y222154D02*
Y225354D01*
G01X1388837Y222154D02*
X1395037D01*
G01X1388837Y225354D02*
Y222154D01*
G01X1395037Y225354D02*
X1388837D01*
G01X1391605Y233588D02*
Y236788D01*
G01X1385405Y233588D02*
X1391605D01*
G01X1385405Y236788D02*
Y233588D01*
G01X1391605Y236788D02*
X1385405D01*
G01X1394893Y824535D02*
X1406893D01*
G01X1394893Y830535D02*
Y824535D01*
G01X1406893Y830535D02*
X1394893D01*
G01Y831841D02*
X1406893D01*
G01X1394893Y837841D02*
Y831841D01*
G01X1393413D02*
Y837841D01*
G01X1381413Y831841D02*
X1393413D01*
G01X1381413Y837841D02*
Y831841D01*
G01X1393413Y830535D02*
X1381413D01*
G01X1393413Y824535D02*
Y830535D01*
G01X1381413Y824535D02*
X1393413D01*
G01X1381413Y830535D02*
Y824535D01*
G01X1380473Y832541D02*
Y837141D01*
G01Y826120D02*
Y830720D01*
G01X1406893Y837841D02*
X1394893D01*
G01X1393413D02*
X1381413D01*
G01X1386402Y930763D02*
X1391002D01*
G01X1386402Y940963D02*
Y930763D01*
G01X1391002D02*
Y940963D01*
G01X1391102Y930763D02*
X1395702D01*
G01X1391102Y940963D02*
Y930763D01*
G01X1381702D02*
X1386302D01*
G01X1381702Y940963D02*
Y930763D01*
G01X1386302D02*
Y940963D01*
G01X1385787Y930406D02*
Y927206D01*
G01X1391987Y930406D02*
X1385787D01*
G01X1391987Y927206D02*
Y930406D01*
G01X1385787Y927206D02*
X1391987D01*
G01X1398559Y930406D02*
X1392359D01*
Y927206D01*
X1398559D01*
Y930406D01*
G01X1389357Y955365D02*
Y943365D01*
G01X1395357D02*
Y955365D01*
G01X1389357Y943365D02*
X1395357D01*
G01X1382547Y955605D02*
Y943605D01*
G01X1388547D02*
Y955605D01*
G01X1382547Y943605D02*
X1388547D01*
G01X1391002Y940963D02*
X1386402D01*
G01X1391002Y935863D02*
X1386402D01*
G01X1395702Y940963D02*
X1391102D01*
G01X1395702Y935863D02*
X1391102D01*
G01X1386302Y940963D02*
X1381702D01*
G01X1386302Y935863D02*
X1381702D01*
G01X1395202Y957859D02*
Y969859D01*
G01X1389202Y957859D02*
X1395202D01*
G01X1389202Y969859D02*
Y957859D01*
G01X1395357Y955365D02*
X1389357D01*
G01X1388202Y957859D02*
Y969859D01*
G01X1382202Y957859D02*
X1388202D01*
G01X1382202Y969859D02*
Y957859D01*
G01X1388547Y955605D02*
X1382547D01*
G01X1395202Y972339D02*
Y984339D01*
G01X1389202Y972339D02*
X1395202D01*
G01X1389202Y984339D02*
Y972339D01*
G01X1395202Y969859D02*
X1389202D01*
G01X1388202Y972339D02*
Y984339D01*
G01X1382202Y972339D02*
X1388202D01*
G01X1382202Y984339D02*
Y972339D01*
G01X1388202Y969859D02*
X1382202D01*
G01X1395202Y986819D02*
Y998819D01*
G01X1389202Y986819D02*
X1395202D01*
G01X1389202Y998819D02*
Y986819D01*
G01X1395202Y984339D02*
X1389202D01*
G01X1388202Y986819D02*
Y998819D01*
G01X1382202Y986819D02*
X1388202D01*
G01X1382202Y998819D02*
Y986819D01*
G01X1388202Y984339D02*
X1382202D01*
G01X1395202Y998819D02*
X1389202D01*
G01X1395202Y1001299D02*
Y1013299D01*
G01X1389202Y1001299D02*
X1395202D01*
G01X1389202Y1013299D02*
Y1001299D01*
G01X1395202Y1013299D02*
X1389202D01*
G01X1382202D02*
Y1001299D01*
G01X1388202Y1013299D02*
X1382202D01*
G01X1388202Y1001299D02*
Y1013299D01*
G01X1382202Y1001299D02*
X1388202D01*
G01Y998819D02*
X1382202D01*
G01X1385873Y1029869D02*
X1397873D01*
G01X1385873Y1035869D02*
Y1029869D01*
G01X1389202Y1027779D02*
Y1015779D01*
G01X1395202Y1027779D02*
X1389202D01*
G01X1395202Y1015779D02*
Y1027779D01*
G01X1389202Y1015779D02*
X1395202D01*
G01X1388202Y1015783D02*
Y1027783D01*
G01X1382202Y1015783D02*
X1388202D01*
G01X1382202Y1027783D02*
Y1015783D01*
G01X1388202Y1027783D02*
X1382202D01*
G01X1397873Y1035869D02*
X1385873D01*
G01X1385667Y1154519D02*
Y1160519D01*
G01X1398167D02*
X1386167D01*
G01Y1154519D02*
X1398167D01*
G01X1386167Y1160519D02*
Y1154519D01*
G01X1385667Y1162569D02*
Y1168569D01*
G01X1398167D02*
X1386167D01*
G01Y1162569D02*
X1398167D01*
G01X1386167Y1168569D02*
Y1162569D01*
G01X1386198Y1262862D02*
X1388438D01*
G01X1387225Y1261237D02*
Y1264487D01*
G01X1391566Y1319543D02*
Y1307543D01*
G01X1397566Y1319543D02*
X1391566D01*
G01Y1307543D02*
X1397566D01*
G01X1399069Y1334996D02*
X1393069D01*
Y1322996D01*
X1399069D01*
Y1334996D01*
G01X1379697Y1315188D02*
X1382897D01*
G01X1379697Y1321388D02*
Y1315188D01*
G01X1382897Y1321388D02*
X1379697D01*
G01X1382897Y1315188D02*
Y1321388D01*
G01X1381678Y1328533D02*
Y1331733D01*
G01X1391472Y1416875D02*
Y1413675D01*
G01X1397672Y1416875D02*
X1391472D01*
G01Y1413675D02*
X1397672D01*
G01X1379845Y1415392D02*
Y1412192D01*
G01X1386045Y1415392D02*
X1379845D01*
G01X1386045Y1412192D02*
Y1415392D01*
G01X1379845Y1412192D02*
X1386045D01*
G01X1379845Y1418904D02*
Y1415704D01*
G01X1386045Y1418904D02*
X1379845D01*
G01X1386045Y1415704D02*
Y1418904D01*
G01X1379845Y1415704D02*
X1386045D01*
G01X1414418Y112008D02*
G03I-9300J0D01*
G01X1420373Y830535D02*
X1408373D01*
G01Y824535D02*
X1420373D01*
G01X1408373Y830535D02*
Y824535D01*
G01X1408370Y831841D02*
X1420370D01*
G01X1408370Y837841D02*
Y831841D01*
G01X1406893Y824535D02*
Y830535D01*
G01Y831841D02*
Y837841D01*
G01X1420370D02*
X1408370D01*
G01X1402202Y930879D02*
Y942879D01*
G01X1396202Y930879D02*
X1402202D01*
G01X1396202Y942879D02*
Y930879D01*
G01X1395702Y930763D02*
Y940963D01*
G01X1396202Y955379D02*
Y943379D01*
G01X1402202D02*
Y955379D01*
G01X1396202Y943379D02*
X1402202D01*
G01Y942879D02*
X1396202D01*
G01X1402202Y957859D02*
Y969859D01*
G01X1396202Y957859D02*
X1402202D01*
G01X1396202Y969859D02*
Y957859D01*
G01X1402202Y955379D02*
X1396202D01*
G01X1402202Y972339D02*
Y984339D01*
G01X1396202Y972339D02*
X1402202D01*
G01X1396202Y984339D02*
Y972339D01*
G01X1402202Y969859D02*
X1396202D01*
G01X1402202Y986819D02*
Y998819D01*
G01X1396202Y986819D02*
X1402202D01*
G01X1396202Y998819D02*
Y986819D01*
G01X1402202Y984339D02*
X1396202D01*
G01X1402202Y998819D02*
X1396202D01*
G01X1402202Y1001299D02*
Y1013299D01*
G01X1396202Y1001299D02*
X1402202D01*
G01X1396202Y1013299D02*
Y1001299D01*
G01X1402202Y1013299D02*
X1396202D01*
G01X1397873Y1029869D02*
Y1035869D01*
G01X1396202Y1027779D02*
Y1015779D01*
G01X1402202Y1027779D02*
X1396202D01*
G01X1402202Y1015779D02*
Y1027779D01*
G01X1396202Y1015779D02*
X1402202D01*
G01X1398167Y1154519D02*
Y1160519D01*
G01X1398667Y1154519D02*
X1410667D01*
G01X1398667Y1160519D02*
Y1154519D01*
G01X1410667Y1160519D02*
X1398667D01*
G01X1410667Y1154519D02*
Y1160519D01*
G01X1423167D02*
X1411167D01*
G01Y1154519D02*
X1423167D01*
G01X1411167Y1160519D02*
Y1154519D01*
G01X1398167Y1162569D02*
Y1168569D01*
G01X1398667Y1162569D02*
X1410667D01*
G01X1398667Y1168569D02*
Y1162569D01*
G01X1410667Y1168569D02*
X1398667D01*
G01X1410667Y1162569D02*
Y1168569D01*
G01X1423167D02*
X1411167D01*
G01Y1162569D02*
X1423167D01*
G01X1411167Y1168569D02*
Y1162569D01*
G01X1406295Y1273179D02*
X1412295D01*
G01X1406295Y1285179D02*
Y1273179D01*
G01X1404235D02*
Y1285179D01*
G01X1398235Y1273179D02*
X1404235D01*
G01X1398235Y1285179D02*
Y1273179D01*
G01X1396379Y1269030D02*
Y1304726D01*
G01X1412295Y1285179D02*
X1406295D01*
G01X1404235D02*
X1398235D01*
G01X1416320Y1306649D02*
Y1309075D01*
G01X1397566Y1307543D02*
Y1319543D01*
G01X1399972D02*
Y1307543D01*
G01X1405972Y1319543D02*
X1399972D01*
G01X1405972Y1307543D02*
Y1319543D01*
G01X1399972Y1307543D02*
X1405972D01*
G01X1411242Y1314629D02*
X1414442D01*
G01X1411242Y1320829D02*
Y1314629D01*
G01X1414442Y1320829D02*
X1411242D01*
G01X1407641Y1331759D02*
Y1328559D01*
G01D02*
X1413841D01*
G01Y1331759D02*
X1407641D01*
G01X1405363Y1400445D02*
X1408563D01*
G01X1405363Y1406645D02*
Y1400445D01*
G01X1408563D02*
Y1406645D01*
G01X1397672Y1413675D02*
Y1416875D01*
G01X1409525Y1413675D02*
X1415725D01*
G01X1409525Y1416875D02*
Y1413675D01*
G01X1415725Y1416875D02*
X1409525D01*
G01X1409515Y1406189D02*
X1415715D01*
G01X1409515Y1409389D02*
Y1406189D01*
G01X1415715Y1409389D02*
X1409515D01*
G01X1408563Y1406645D02*
X1405363D01*
G01X1425000Y723544D02*
Y720344D01*
G01D02*
X1431200D01*
G01X1424997Y719465D02*
Y716265D01*
G01X1431197Y719465D02*
X1424997D01*
G01Y716265D02*
X1431197D01*
G01X1425860Y728292D02*
X1426167Y728344D01*
X1426435Y728550D01*
X1426665Y728860D01*
X1426818Y729222D01*
X1426895Y729635D01*
Y730049D01*
X1426818Y730462D01*
X1426665Y730824D01*
X1426435Y731134D01*
X1426167Y731340D01*
X1425860Y731392D01*
X1425553Y731340D01*
X1425285Y731134D01*
X1425055Y730824D01*
X1424902Y730462D01*
X1424825Y730049D01*
Y729635D01*
X1424902Y729222D01*
X1425055Y728860D01*
X1425285Y728550D01*
X1425553Y728344D01*
X1425860Y728292D01*
G01X1425553Y729119D02*
X1425093Y728292D01*
G01X1422760D02*
Y731392D01*
X1423220Y730772D01*
G01Y728292D02*
X1422300D01*
G01X1420503Y728757D02*
X1420273Y728499D01*
X1420005Y728344D01*
X1419660Y728292D01*
X1419315Y728395D01*
X1419047Y728602D01*
X1418855Y728964D01*
X1418817Y729377D01*
X1418893Y729790D01*
X1419085Y730049D01*
X1419353Y730255D01*
X1419622Y730307D01*
X1419890Y730255D01*
X1420235Y730049D01*
X1420120Y731392D01*
X1419085D01*
G01X1431200Y723544D02*
X1425000D01*
G01X1421853Y824535D02*
X1433853D01*
G01X1421853Y830535D02*
Y824535D01*
G01X1433853Y830535D02*
X1421853D01*
G01X1421850Y831841D02*
X1433850D01*
G01X1421850Y837841D02*
Y831841D01*
G01X1420373Y824535D02*
Y830535D01*
G01X1420370Y831841D02*
Y837841D01*
G01X1433850D02*
X1421850D01*
G01X1423167Y1154519D02*
Y1160519D01*
G01X1423667Y1154519D02*
X1435667D01*
G01X1423667Y1160519D02*
Y1154519D01*
G01X1435667Y1160519D02*
X1423667D01*
G01X1423167Y1162569D02*
Y1168569D01*
G01X1423667Y1162569D02*
X1435667D01*
G01X1423667Y1168569D02*
Y1162569D01*
G01X1435667Y1168569D02*
X1423667D01*
G01X1422369Y1262874D02*
X1424609D01*
G01X1423396Y1261249D02*
Y1264499D01*
G01X1412295Y1273179D02*
Y1285179D01*
G01X1414834Y1269042D02*
X1432550D01*
G01X1414834Y1304738D02*
Y1269042D01*
G01X1432550Y1304738D02*
X1414834D01*
G01X1423694Y1319920D02*
Y1307920D01*
G01X1429694Y1319920D02*
X1423694D01*
G01Y1307920D02*
X1429694D01*
G01X1431197Y1334996D02*
X1425197D01*
Y1322996D01*
X1431197D01*
Y1334996D01*
G01X1414442Y1314629D02*
Y1320829D01*
G01X1413841Y1328559D02*
Y1331759D01*
G01X1427200Y1400348D02*
X1433400D01*
G01X1427200Y1403548D02*
Y1400348D01*
G01X1433400Y1403548D02*
X1427200D01*
G01X1415725Y1413675D02*
Y1416875D01*
G01X1415715Y1406189D02*
Y1409389D01*
G01X1424835Y1415869D02*
X1428035D01*
G01X1424835Y1422069D02*
Y1415869D01*
G01X1428035D02*
Y1422069D01*
G01X1424576Y1413708D02*
Y1410508D01*
G01X1430776Y1413708D02*
X1424576D01*
G01Y1410508D02*
X1430776D01*
G01X1424315Y1406629D02*
X1430515D01*
G01X1424315Y1409829D02*
Y1406629D01*
G01X1430515Y1409829D02*
X1424315D01*
G01X1418180Y1409904D02*
Y1413104D01*
G01X1411980Y1409904D02*
X1418180D01*
G01X1411980Y1413104D02*
Y1409904D01*
G01X1418180Y1413104D02*
X1411980D01*
G01X1418695Y1419059D02*
Y1422259D01*
G01X1412495Y1419059D02*
X1418695D01*
G01X1412495Y1422259D02*
Y1419059D01*
G01X1428035Y1422069D02*
X1424835D01*
G01X1418695Y1422259D02*
X1412495D01*
G01X1420881Y1429548D02*
Y1426348D01*
G01X1427081Y1429548D02*
X1420881D01*
G01X1427081Y1426348D02*
Y1429548D01*
G01X1420881Y1426348D02*
X1427081D01*
G01Y1422649D02*
Y1425849D01*
G01X1420881Y1422649D02*
X1427081D01*
G01X1420881Y1425849D02*
Y1422649D01*
G01X1427081Y1425849D02*
X1420881D01*
G01X1441487Y715625D02*
Y726119D01*
G01X1432825Y715625D02*
X1441487D01*
G01X1432825Y718972D02*
Y715625D01*
G01X1435025Y720872D02*
X1432825Y718972D01*
G01Y722772D02*
X1435025Y720872D01*
G01X1441797Y710975D02*
Y714175D01*
G01X1435597Y710975D02*
X1441797D01*
G01X1435597Y714175D02*
Y710975D01*
G01X1441797Y714175D02*
X1435597D01*
G01X1431200Y720344D02*
Y723544D01*
G01X1431197Y716265D02*
Y719465D01*
G01X1441487Y726119D02*
X1432825D01*
G01D02*
Y722772D01*
G01X1446618Y729088D02*
X1443418D01*
G01Y722888D02*
X1446618D01*
G01X1443418Y729088D02*
Y722888D01*
G01X1430160Y730612D02*
X1436360D01*
G01D02*
Y733812D01*
G01D02*
X1430160D01*
G01D02*
Y730612D01*
G01X1451333Y755642D02*
Y753420D01*
X1451180Y752955D01*
X1450873Y752645D01*
X1450490Y752542D01*
X1450107Y752645D01*
X1449800Y752955D01*
X1449647Y753420D01*
Y755642D01*
G01X1448118Y755125D02*
X1447888Y755435D01*
X1447620Y755590D01*
X1447313Y755642D01*
X1446930Y755539D01*
X1446662Y755280D01*
X1446585Y754970D01*
X1446623Y754660D01*
X1446777Y754402D01*
X1447543Y753885D01*
X1447888Y753524D01*
X1448118Y753007D01*
X1448195Y752542D01*
X1446585D01*
G01X1444290D02*
X1444022Y752594D01*
X1443715Y752749D01*
X1443523Y753007D01*
X1443447Y753369D01*
X1443523Y753730D01*
X1443753Y754040D01*
X1444098Y754195D01*
X1444482D01*
X1444712Y754299D01*
X1444903Y754557D01*
X1444980Y754919D01*
X1444865Y755280D01*
X1444597Y755539D01*
X1444290Y755642D01*
X1443983Y755539D01*
X1443715Y755280D01*
X1443600Y754919D01*
X1443677Y754557D01*
X1443868Y754299D01*
X1444098Y754195D01*
X1444482D01*
X1444827Y754040D01*
X1445057Y753730D01*
X1445133Y753369D01*
X1445057Y753007D01*
X1444865Y752749D01*
X1444558Y752594D01*
X1444290Y752542D01*
G01X1447333Y830535D02*
X1435333D01*
G01Y824535D02*
X1447333D01*
G01X1435333Y830535D02*
Y824535D01*
G01X1435330Y831841D02*
X1447330D01*
G01X1435330Y837841D02*
Y831841D01*
G01X1433853Y824535D02*
Y830535D01*
G01X1433850Y831841D02*
Y837841D01*
G01X1447330D02*
X1435330D01*
G01X1431421Y941897D02*
Y929897D01*
G01X1437421D02*
Y941897D01*
G01X1431421Y929897D02*
X1437421D01*
G01X1437921Y930763D02*
X1442521D01*
G01X1437921Y940963D02*
Y930763D01*
G01X1442521D02*
Y940963D01*
G01X1442621Y930763D02*
X1447221D01*
G01X1442621Y940963D02*
Y930763D01*
G01X1444287Y943475D02*
Y955475D01*
G01X1438287Y943475D02*
X1444287D01*
G01X1438287Y955475D02*
Y943475D01*
G01X1437421Y943379D02*
Y955379D01*
G01X1431421Y943379D02*
X1437421D01*
G01X1431421Y955379D02*
Y943379D01*
G01X1437421Y941897D02*
X1431421D01*
G01X1442521Y940963D02*
X1437921D01*
G01X1442521Y935863D02*
X1437921D01*
G01X1447221Y940963D02*
X1442621D01*
G01X1447221Y935863D02*
X1442621D01*
G01X1438421Y957859D02*
X1444421D01*
G01X1438421Y969859D02*
Y957859D01*
G01X1444287Y955475D02*
X1438287D01*
G01X1437421Y957859D02*
Y969859D01*
G01X1431421Y957859D02*
X1437421D01*
G01X1431421Y969859D02*
Y957859D01*
G01X1437421Y955379D02*
X1431421D01*
G01X1438421Y972339D02*
X1444421D01*
G01X1438421Y984339D02*
Y972339D01*
G01X1444421Y969859D02*
X1438421D01*
G01X1437421Y972339D02*
Y984339D01*
G01X1431421Y972339D02*
X1437421D01*
G01X1431421Y984339D02*
Y972339D01*
G01X1437421Y969859D02*
X1431421D01*
G01X1438421Y986819D02*
X1444421D01*
G01X1438421Y998819D02*
Y986819D01*
G01X1444421Y984339D02*
X1438421D01*
G01X1437421Y986819D02*
Y998819D01*
G01X1431421Y986819D02*
X1437421D01*
G01X1431421Y998819D02*
Y986819D01*
G01X1437421Y984339D02*
X1431421D01*
G01X1444421Y998819D02*
X1438421D01*
G01Y1001299D02*
X1444421D01*
G01X1438421Y1013299D02*
Y1001299D01*
G01X1444421Y1013299D02*
X1438421D01*
G01X1437421Y998819D02*
X1431421D01*
G01X1437421Y1001299D02*
Y1013299D01*
G01X1431421Y1001299D02*
X1437421D01*
G01X1431421Y1013299D02*
Y1001299D01*
G01X1437421Y1013299D02*
X1431421D01*
G01X1438421Y1027779D02*
Y1015779D01*
G01X1444421Y1027779D02*
X1438421D01*
G01Y1015779D02*
X1444421D01*
G01X1435092Y1029869D02*
X1447092D01*
G01X1435092Y1035869D02*
Y1029869D01*
G01X1431421Y1027779D02*
Y1015779D01*
G01X1437421Y1027779D02*
X1431421D01*
G01X1437421Y1015779D02*
Y1027779D01*
G01X1431421Y1015779D02*
X1437421D01*
G01X1447092Y1035869D02*
X1435092D01*
G01X1435667Y1154519D02*
Y1160519D01*
G01X1448167D02*
X1436167D01*
G01Y1154519D02*
X1448167D01*
G01X1436167Y1160519D02*
Y1154519D01*
G01X1435667Y1162569D02*
Y1168569D01*
G01X1448167D02*
X1436167D01*
G01Y1162569D02*
X1448167D01*
G01X1436167Y1168569D02*
Y1162569D01*
G01X1441734Y1273179D02*
Y1285179D01*
G01X1435734Y1273179D02*
X1441734D01*
G01X1435734Y1285179D02*
Y1273179D01*
G01X1432550Y1269042D02*
Y1304738D01*
G01X1441734Y1285179D02*
X1435734D01*
G01X1443252Y1276861D02*
X1446452D01*
G01X1443252Y1283061D02*
Y1276861D01*
G01X1446452Y1283061D02*
X1443252D01*
G01X1429694Y1307920D02*
Y1319920D01*
G01X1432100D02*
Y1307920D01*
G01X1438100Y1319920D02*
X1432100D01*
G01X1438100Y1307920D02*
Y1319920D01*
G01X1432100Y1307920D02*
X1438100D01*
G01X1443331Y1314591D02*
X1446531D01*
G01X1443331Y1320791D02*
Y1314591D01*
G01X1446531Y1320791D02*
X1443331D01*
G01X1439618Y1331912D02*
Y1328712D01*
G01D02*
X1445818D01*
G01Y1331912D02*
X1439618D01*
G01X1433400Y1400348D02*
Y1403548D01*
G01X1430776Y1410508D02*
Y1413708D01*
G01X1430515Y1406629D02*
Y1409829D01*
G01X1443360Y1569172D02*
Y1572372D01*
G01X1437160Y1569172D02*
X1443360D01*
G01X1437160Y1572372D02*
Y1569172D01*
G01X1443360Y1572372D02*
X1437160D01*
G01X1451620Y150962D02*
Y147762D01*
G01X1457820Y150962D02*
X1451620D01*
G01X1457820Y147762D02*
Y150962D01*
G01X1451620Y147762D02*
X1457820D01*
G01X1451620Y154962D02*
Y151762D01*
G01X1457820D02*
Y154962D01*
G01X1451620Y151762D02*
X1457820D01*
G01Y143762D02*
Y146962D01*
G01X1451620Y143762D02*
X1457820D01*
G01X1451620Y146962D02*
Y143762D01*
G01X1457820Y146962D02*
X1451620D01*
G01Y163462D02*
Y160262D01*
G01X1457820Y163462D02*
X1451620D01*
G01X1457820Y160262D02*
Y163462D01*
G01X1451620Y160262D02*
X1457820D01*
G01Y154962D02*
X1451620D01*
G01Y167462D02*
Y164262D01*
G01X1457820Y167462D02*
X1451620D01*
G01X1457820Y164262D02*
Y167462D01*
G01X1451620Y164262D02*
X1457820D01*
G01X1451620Y159462D02*
Y156262D01*
G01X1457820Y159462D02*
X1451620D01*
G01X1457820Y156262D02*
Y159462D01*
G01X1451620Y156262D02*
X1457820D01*
G01X1451620Y171462D02*
Y168262D01*
G01X1457820D02*
Y171462D01*
G01X1451620Y168262D02*
X1457820D01*
G01X1451620Y175462D02*
Y172262D01*
G01X1457820Y175462D02*
X1451620D01*
G01X1457820Y172262D02*
Y175462D01*
G01X1451620Y172262D02*
X1457820D01*
G01X1451620Y179462D02*
Y176262D01*
G01X1457820Y179462D02*
X1451620D01*
G01X1457820Y176262D02*
Y179462D01*
G01X1451620Y176262D02*
X1457820D01*
G01X1451620Y183462D02*
Y180262D01*
G01X1457820Y183462D02*
X1451620D01*
G01X1457820Y180262D02*
Y183462D01*
G01X1451620Y180262D02*
X1457820D01*
G01Y171462D02*
X1451620D01*
G01X1460396Y730834D02*
Y743038D01*
G01X1448872Y730834D02*
X1460396D01*
G01X1448872Y743038D02*
Y730834D01*
G01X1460418Y729088D02*
X1457218D01*
G01X1460418Y722888D02*
Y729088D01*
G01X1457218Y722888D02*
X1460418D01*
G01X1457218Y729088D02*
Y722888D01*
G01X1446618D02*
Y729088D01*
G01X1450718D02*
X1447518D01*
G01X1450718Y722888D02*
Y729088D01*
G01X1447518Y722888D02*
X1450718D01*
G01X1447518Y729088D02*
Y722888D01*
G01X1454818Y729088D02*
X1451618D01*
G01X1454818Y722888D02*
Y729088D01*
G01X1451618Y722888D02*
X1454818D01*
G01X1451618Y729088D02*
Y722888D01*
G01X1451634Y743038D02*
X1448872D01*
G01X1454634Y739936D02*
X1451634Y743038D01*
G01X1457736D02*
X1454634Y739936D01*
G01X1460396Y743038D02*
X1457736D01*
G01X1458607Y747905D02*
Y744705D01*
G01X1464807Y747905D02*
X1458607D01*
G01Y744705D02*
X1464807D01*
G01X1451047D02*
Y747905D01*
G01X1444847Y744705D02*
X1451047D01*
G01X1444847Y747905D02*
Y744705D01*
G01X1451047Y747905D02*
X1444847D01*
G01X1447333Y824535D02*
Y830535D01*
G01X1447330Y831841D02*
Y837841D01*
G01X1448810Y831841D02*
X1460810D01*
G01X1448810Y837841D02*
Y831841D01*
G01X1448813Y824535D02*
X1460813D01*
G01X1448813Y830535D02*
Y824535D01*
G01X1460813Y830535D02*
X1448813D01*
G01X1460810Y837841D02*
X1448810D01*
G01X1447221Y930763D02*
Y940963D01*
G01X1451921Y930763D02*
Y940963D01*
G01X1447321Y930763D02*
X1451921D01*
G01X1447321Y940963D02*
Y930763D01*
G01X1445127Y955275D02*
Y943275D01*
G01X1451127D02*
Y955275D01*
G01X1445127Y943275D02*
X1451127D01*
G01X1451921Y940963D02*
X1447321D01*
G01Y935863D02*
X1451921D01*
G01X1451421Y957859D02*
Y969859D01*
G01X1445421Y957859D02*
X1451421D01*
G01X1445421Y969859D02*
Y957859D01*
G01X1444421D02*
Y969859D01*
G01X1451127Y955275D02*
X1445127D01*
G01X1451421Y972339D02*
Y984339D01*
G01X1445421Y972339D02*
X1451421D01*
G01X1445421Y984339D02*
Y972339D01*
G01X1444421D02*
Y984339D01*
G01X1451421Y969859D02*
X1445421D01*
G01X1451421Y986819D02*
Y998819D01*
G01X1445421Y986819D02*
X1451421D01*
G01X1445421Y998819D02*
Y986819D01*
G01X1444421D02*
Y998819D01*
G01X1451421Y984339D02*
X1445421D01*
G01X1451421Y998819D02*
X1445421D01*
G01X1451421Y1001299D02*
Y1013299D01*
G01X1445421Y1001299D02*
X1451421D01*
G01X1445421Y1013299D02*
Y1001299D01*
G01X1451421Y1013299D02*
X1445421D01*
G01X1444421Y1001299D02*
Y1013299D01*
G01X1445421Y1027779D02*
Y1015779D01*
G01X1451421Y1027779D02*
X1445421D01*
G01X1451421Y1015779D02*
Y1027779D01*
G01X1445421Y1015779D02*
X1451421D01*
G01X1444421D02*
Y1027779D01*
G01X1447092Y1029869D02*
Y1035869D01*
G01X1451043Y1028213D02*
Y1034413D01*
X1447843D01*
Y1028213D01*
X1451043D01*
G01X1448167Y1154519D02*
Y1160519D01*
G01X1448667Y1154519D02*
X1460667D01*
G01X1448667Y1160519D02*
Y1154519D01*
G01X1460667Y1160519D02*
X1448667D01*
G01X1460667Y1154519D02*
Y1160519D01*
G01X1448167Y1162569D02*
Y1168569D01*
G01X1448667Y1162569D02*
X1460667D01*
G01X1448667Y1168569D02*
Y1162569D01*
G01X1460667Y1168569D02*
X1448667D01*
G01X1460667Y1162569D02*
Y1168569D01*
G01X1454842Y1273179D02*
Y1285179D01*
G01X1448842Y1273179D02*
X1454842D01*
G01X1448842Y1285179D02*
Y1273179D01*
G01X1457242D02*
X1463242D01*
G01X1457242Y1285179D02*
Y1273179D01*
G01X1454842Y1285179D02*
X1448842D01*
G01X1463242D02*
X1457242D01*
G01X1446452Y1276861D02*
Y1283061D01*
G01X1455822Y1319920D02*
Y1307920D01*
G01X1461822Y1319920D02*
X1455822D01*
G01Y1307920D02*
X1461822D01*
G01X1462583Y1334923D02*
X1456583D01*
Y1322923D01*
X1462583D01*
Y1334923D01*
G01X1446531Y1314591D02*
Y1320791D01*
G01X1445818Y1328712D02*
Y1331912D01*
G01X1454134Y1394295D02*
X1457334D01*
G01X1454134Y1400495D02*
Y1394295D01*
G01X1457334Y1400495D02*
X1454134D01*
G01X1457334Y1394295D02*
Y1400495D01*
G01X1461031D02*
X1457831D01*
G01Y1394295D02*
X1461031D01*
G01X1457831Y1400495D02*
Y1394295D01*
G01X1449873Y1409739D02*
Y1406539D01*
G01X1456073Y1409739D02*
X1449873D01*
G01X1456073Y1406539D02*
Y1409739D01*
G01X1449873Y1406539D02*
X1456073D01*
G01X1464127Y1427042D02*
Y1430142D01*
X1463207D01*
X1462900Y1429987D01*
X1462670Y1429625D01*
X1462593Y1429212D01*
X1462670Y1428799D01*
X1462862Y1428489D01*
X1463207Y1428334D01*
X1464127D01*
G01X1461027Y1427662D02*
X1460835Y1427352D01*
X1460605Y1427145D01*
X1460337Y1427042D01*
X1460030Y1427145D01*
X1459800Y1427352D01*
X1459570Y1427662D01*
X1459493Y1428075D01*
Y1430142D01*
G01X1457888Y1428334D02*
X1457620Y1428695D01*
X1457390Y1428902D01*
X1457083Y1429005D01*
X1456815Y1428902D01*
X1456623Y1428695D01*
X1456470Y1428385D01*
X1456432Y1428024D01*
X1456470Y1427714D01*
X1456623Y1427404D01*
X1456853Y1427145D01*
X1457122Y1427042D01*
X1457428Y1427145D01*
X1457697Y1427455D01*
X1457850Y1427920D01*
X1457888Y1428437D01*
X1457812Y1429109D01*
X1457697Y1429470D01*
X1457505Y1429832D01*
X1457237Y1430090D01*
X1456968Y1430142D01*
X1456700Y1430039D01*
X1456508Y1429780D01*
G01X1453600Y1427042D02*
Y1430142D01*
X1455018Y1427920D01*
X1453102D01*
G01X1465027Y1432612D02*
Y1435712D01*
X1464107D01*
X1463800Y1435557D01*
X1463570Y1435195D01*
X1463493Y1434782D01*
X1463570Y1434369D01*
X1463762Y1434059D01*
X1464107Y1433904D01*
X1465027D01*
G01X1461927Y1433232D02*
X1461735Y1432922D01*
X1461505Y1432715D01*
X1461237Y1432612D01*
X1460930Y1432715D01*
X1460700Y1432922D01*
X1460470Y1433232D01*
X1460393Y1433645D01*
Y1435712D01*
G01X1458788Y1433904D02*
X1458520Y1434265D01*
X1458290Y1434472D01*
X1457983Y1434575D01*
X1457715Y1434472D01*
X1457523Y1434265D01*
X1457370Y1433955D01*
X1457332Y1433594D01*
X1457370Y1433284D01*
X1457523Y1432974D01*
X1457753Y1432715D01*
X1458022Y1432612D01*
X1458328Y1432715D01*
X1458597Y1433025D01*
X1458750Y1433490D01*
X1458788Y1434007D01*
X1458712Y1434679D01*
X1458597Y1435040D01*
X1458405Y1435402D01*
X1458137Y1435660D01*
X1457868Y1435712D01*
X1457600Y1435609D01*
X1457408Y1435350D01*
G01X1455803Y1433077D02*
X1455573Y1432819D01*
X1455305Y1432664D01*
X1454960Y1432612D01*
X1454615Y1432715D01*
X1454347Y1432922D01*
X1454155Y1433284D01*
X1454117Y1433697D01*
X1454193Y1434110D01*
X1454385Y1434369D01*
X1454653Y1434575D01*
X1454922Y1434627D01*
X1455190Y1434575D01*
X1455535Y1434369D01*
X1455420Y1435712D01*
X1454385D01*
G01X1460294Y1449919D02*
Y1437919D01*
G01X1466294Y1449919D02*
X1460294D01*
G01Y1437919D02*
X1466294D01*
G01X1463120Y146962D02*
Y143762D01*
G01X1469320Y146962D02*
X1463120D01*
G01X1469320Y143762D02*
Y146962D01*
G01X1463120Y143762D02*
X1469320D01*
G01Y168262D02*
Y171462D01*
G01X1463120Y168262D02*
X1469320D01*
G01X1463120Y171462D02*
Y168262D01*
G01X1469320Y171462D02*
X1463120D01*
G01X1476258Y282556D02*
X1488258D01*
G01X1476258Y288556D02*
Y282556D01*
G01X1476158Y290756D02*
X1488158D01*
G01X1476158Y296756D02*
Y290756D01*
G01X1488158Y296756D02*
X1476158D01*
G01X1488258Y288556D02*
X1476258D01*
G01X1476358Y313356D02*
X1488358D01*
G01X1476358Y319356D02*
Y313356D01*
G01X1476158Y298956D02*
X1488158D01*
G01X1476158Y304956D02*
Y298956D01*
G01X1488158Y304956D02*
X1476158D01*
G01X1488358Y319356D02*
X1476358D01*
G01X1470547Y737035D02*
Y743235D01*
G01X1467347Y737035D02*
X1470547D01*
G01X1467347Y743235D02*
Y737035D01*
G01X1467467Y729755D02*
X1470667D01*
G01X1467467Y735955D02*
Y729755D01*
G01X1470667Y735955D02*
X1467467D01*
G01X1470667Y729755D02*
Y735955D01*
G01X1464807Y744705D02*
Y747905D01*
G01X1472256Y753901D02*
X1469056D01*
G01X1472256Y747701D02*
Y753901D01*
G01X1469056Y747701D02*
X1472256D01*
G01X1469056Y753901D02*
Y747701D01*
G01X1476256Y753901D02*
X1473056D01*
G01X1476256Y747701D02*
Y753901D01*
G01X1473056Y747701D02*
X1476256D01*
G01X1473056Y753901D02*
Y747701D01*
G01X1470547Y743235D02*
X1467347D01*
G01X1460810Y831841D02*
Y837841D01*
G01X1460813Y824535D02*
Y830535D01*
G01X1463242Y1273179D02*
Y1285179D01*
G01X1475449Y1286512D02*
Y1298512D01*
G01X1469449Y1286512D02*
X1475449D01*
G01X1469449Y1298512D02*
Y1286512D01*
G01X1465384Y1276814D02*
X1468584D01*
G01X1465384Y1283014D02*
Y1276814D01*
G01X1468584Y1283014D02*
X1465384D01*
G01X1468584Y1276814D02*
Y1283014D01*
G01X1475449Y1298512D02*
X1469449D01*
G01X1461822Y1307920D02*
Y1319920D01*
G01X1464228D02*
Y1307920D01*
G01X1470228Y1319920D02*
X1464228D01*
G01X1470228Y1307920D02*
Y1319920D01*
G01X1464228Y1307920D02*
X1470228D01*
G01X1478920Y1318889D02*
Y1321315D01*
G01X1475554Y1327998D02*
X1478754D01*
G01X1475554Y1334198D02*
Y1327998D01*
G01X1478754Y1334198D02*
X1475554D01*
G01X1470860Y1333918D02*
X1474060D01*
G01X1470860Y1340118D02*
Y1333918D01*
G01X1474060D02*
Y1340118D01*
G01D02*
X1470860D01*
G01X1464849Y1400495D02*
X1461649D01*
G01X1464849Y1394295D02*
Y1400495D01*
G01X1461649Y1394295D02*
X1464849D01*
G01X1461649Y1400495D02*
Y1394295D01*
G01X1461031D02*
Y1400495D01*
G01X1464147Y1412265D02*
X1467347D01*
G01X1464147Y1418465D02*
Y1412265D01*
G01X1467347Y1418465D02*
X1464147D01*
G01X1467347Y1412265D02*
Y1418465D01*
G01X1466294Y1437919D02*
Y1449919D01*
G01X1468694D02*
Y1437919D01*
G01X1474694Y1449919D02*
X1468694D01*
G01X1474694Y1437919D02*
Y1449919D01*
G01X1468694Y1437919D02*
X1474694D01*
G01X1483781Y-23211D02*
Y-39811D01*
X1493381D01*
Y-23211D01*
X1483781D01*
G01Y-3211D02*
Y-19811D01*
X1493381D01*
Y-3211D01*
X1483781D01*
G01Y16789D02*
Y189D01*
X1493381D01*
Y16789D01*
X1483781D01*
G01X1488258Y282556D02*
Y288556D01*
G01X1488158Y290756D02*
Y296756D01*
G01X1488358Y313356D02*
Y319356D01*
G01X1488158Y298956D02*
Y304956D01*
G01X1479949Y310857D02*
Y307657D01*
G01X1486149Y310857D02*
X1479949D01*
G01X1486149Y307657D02*
Y310857D01*
G01X1479949Y307657D02*
X1486149D01*
G01X1477056Y747701D02*
X1480256D01*
G01X1477056Y753901D02*
Y747701D01*
G01X1480256Y753901D02*
X1477056D01*
G01X1480256Y747701D02*
Y753901D01*
G01X1489392Y748064D02*
X1492592D01*
G01X1489392Y754264D02*
Y748064D01*
G01X1492592Y754264D02*
X1489392D01*
G01X1492592Y748064D02*
Y754264D01*
G01X1485141Y747702D02*
X1488341D01*
G01X1485141Y753902D02*
Y747702D01*
G01X1488341Y753902D02*
X1485141D01*
G01X1488341Y747702D02*
Y753902D01*
G01X1484351D02*
X1481151D01*
G01X1484351Y747702D02*
Y753902D01*
G01X1481151Y747702D02*
X1484351D01*
G01X1481151Y753902D02*
Y747702D01*
G01X1511368Y1171318D02*
G03I-9950J0D01*
G01X1484840Y1274888D02*
X1487080D01*
G01X1485867Y1273263D02*
Y1276513D01*
G01X1477305Y1281056D02*
X1495021D01*
G01X1477305Y1316752D02*
Y1281056D01*
G01X1487950Y1333346D02*
Y1321346D01*
G01D02*
X1493950D01*
G01X1495021Y1316752D02*
X1477305D01*
G01X1493950Y1333346D02*
X1487950D01*
G01X1488340Y1337378D02*
X1494340D01*
G01X1488340Y1349378D02*
Y1337378D01*
G01X1478754Y1327998D02*
Y1334198D01*
G01X1494340Y1349378D02*
X1488340D01*
G01X1477094Y1449919D02*
Y1437919D01*
G01X1483094Y1449919D02*
X1477094D01*
G01X1483094Y1437919D02*
Y1449919D01*
G01X1477094Y1437919D02*
X1483094D01*
G01X1576378Y1646023D02*
X1486221D01*
G01D02*
Y1684312D01*
G01X1551087Y1654782D02*
Y1662282D01*
X1548847D01*
X1548100Y1661907D01*
X1547540Y1661032D01*
X1547353Y1660032D01*
X1547540Y1659032D01*
X1548007Y1658282D01*
X1548847Y1657907D01*
X1551087D01*
G01X1543587Y1654782D02*
Y1662282D01*
X1541253D01*
X1540507Y1661907D01*
X1540040Y1661407D01*
X1539853Y1660407D01*
X1540040Y1659407D01*
X1540600Y1658782D01*
X1541253Y1658407D01*
X1543587D01*
G01X1541253D02*
X1539853Y1654782D01*
G01X1532353D02*
X1536087D01*
Y1662282D01*
X1532353D01*
G01X1533847Y1658657D02*
X1536087D01*
G01X1528680Y1655782D02*
X1527933Y1655157D01*
X1527093Y1654782D01*
X1526347D01*
X1525600Y1655157D01*
X1525040Y1655782D01*
X1524760Y1656657D01*
X1524947Y1657532D01*
X1525413Y1658282D01*
X1526253Y1658782D01*
X1527373Y1659032D01*
X1528027Y1659532D01*
X1528307Y1660407D01*
X1528120Y1661282D01*
X1527653Y1661907D01*
X1527000Y1662282D01*
X1526347D01*
X1525693Y1662032D01*
X1525133Y1661407D01*
G01X1521180Y1655782D02*
X1520433Y1655157D01*
X1519593Y1654782D01*
X1518847D01*
X1518100Y1655157D01*
X1517540Y1655782D01*
X1517260Y1656657D01*
X1517447Y1657532D01*
X1517913Y1658282D01*
X1518753Y1658782D01*
X1519873Y1659032D01*
X1520527Y1659532D01*
X1520807Y1660407D01*
X1520620Y1661282D01*
X1520153Y1661907D01*
X1519500Y1662282D01*
X1518847D01*
X1518193Y1662032D01*
X1517633Y1661407D01*
G01X1512933Y1657282D02*
X1510507D01*
G01X1505993Y1654782D02*
Y1662282D01*
X1502447D01*
G01X1503753Y1658657D02*
X1505993D01*
G01X1497840Y1662282D02*
X1495600D01*
G01X1496720D02*
Y1654782D01*
G01X1497840D02*
X1495600D01*
G01X1489220Y1662282D02*
Y1654782D01*
G01X1491367Y1662282D02*
X1487073D01*
G01X1486221Y1699222D02*
Y1728752D01*
G01Y1737182D02*
Y1781456D01*
G01D02*
X1576378D01*
G01X1505620Y-37117D02*
X1505310Y-36925D01*
X1505103Y-36695D01*
X1505000Y-36427D01*
X1505103Y-36120D01*
X1505310Y-35890D01*
X1505620Y-35660D01*
X1506033Y-35583D01*
X1508100D01*
G01X1505000Y-33250D02*
X1508100D01*
X1507480Y-33710D01*
G01X1505000D02*
Y-32790D01*
G01Y-30150D02*
X1508100D01*
X1507480Y-30610D01*
G01X1505000D02*
Y-29690D01*
G01X1506292Y-27778D02*
X1506653Y-27510D01*
X1506860Y-27280D01*
X1506963Y-26973D01*
X1506860Y-26705D01*
X1506653Y-26513D01*
X1506343Y-26360D01*
X1505982Y-26322D01*
X1505672Y-26360D01*
X1505362Y-26513D01*
X1505103Y-26743D01*
X1505000Y-27012D01*
X1505103Y-27318D01*
X1505413Y-27587D01*
X1505878Y-27740D01*
X1506395Y-27778D01*
X1507067Y-27702D01*
X1507428Y-27587D01*
X1507790Y-27395D01*
X1508048Y-27127D01*
X1508100Y-26858D01*
X1507997Y-26590D01*
X1507738Y-26398D01*
G01X1506120Y-16617D02*
X1505810Y-16425D01*
X1505603Y-16195D01*
X1505500Y-15927D01*
X1505603Y-15620D01*
X1505810Y-15390D01*
X1506120Y-15160D01*
X1506533Y-15083D01*
X1508600D01*
G01X1505500Y-12750D02*
X1508600D01*
X1507980Y-13210D01*
G01X1505500D02*
Y-12290D01*
G01Y-9650D02*
X1508600D01*
X1507980Y-10110D01*
G01X1505500D02*
Y-9190D01*
G01Y-6627D02*
X1506172Y-6550D01*
X1506740Y-6435D01*
X1507257Y-6282D01*
X1507825Y-6090D01*
X1508600Y-5783D01*
Y-7317D01*
G01X1506120Y4883D02*
X1505810Y5075D01*
X1505603Y5305D01*
X1505500Y5573D01*
X1505603Y5880D01*
X1505810Y6110D01*
X1506120Y6340D01*
X1506533Y6417D01*
X1508600D01*
G01X1506792Y8022D02*
X1507153Y8290D01*
X1507360Y8520D01*
X1507463Y8827D01*
X1507360Y9095D01*
X1507153Y9287D01*
X1506843Y9440D01*
X1506482Y9478D01*
X1506172Y9440D01*
X1505862Y9287D01*
X1505603Y9057D01*
X1505500Y8788D01*
X1505603Y8482D01*
X1505913Y8213D01*
X1506378Y8060D01*
X1506895Y8022D01*
X1507567Y8098D01*
X1507928Y8213D01*
X1508290Y8405D01*
X1508548Y8673D01*
X1508600Y8942D01*
X1508497Y9210D01*
X1508238Y9402D01*
G01X1505500Y12310D02*
X1508600D01*
X1506378Y10892D01*
Y12808D01*
G01X1508837Y312225D02*
X1512037D01*
G01X1508837Y318425D02*
Y312225D01*
G01X1512037Y318425D02*
X1508837D01*
G01X1503996Y735927D02*
X1500796D01*
G01X1503996Y729727D02*
Y735927D01*
G01X1500796Y729727D02*
X1503996D01*
G01X1500796Y735927D02*
Y729727D01*
G01X1508616Y732866D02*
Y739066D01*
G01X1505416Y732866D02*
X1508616D01*
G01X1505416Y739066D02*
Y732866D01*
G01X1500845Y754365D02*
X1497645D01*
G01X1500845Y748165D02*
Y754365D01*
G01X1497645Y748165D02*
X1500845D01*
G01X1497645Y754365D02*
Y748165D01*
G01X1507076Y739715D02*
Y742915D01*
G01X1500876Y739715D02*
X1507076D01*
G01X1500876Y742915D02*
Y739715D01*
G01X1507076Y742915D02*
X1500876D01*
G01X1503942Y743640D02*
Y746840D01*
G01X1497742Y743640D02*
X1503942D01*
G01X1497742Y746840D02*
Y743640D01*
G01X1503942Y746840D02*
X1497742D01*
G01X1502045Y748165D02*
X1505245D01*
G01X1502045Y754365D02*
Y748165D01*
G01X1505245Y754365D02*
X1502045D01*
G01X1505245Y748165D02*
Y754365D01*
G01X1496563Y754262D02*
X1493363D01*
G01X1496563Y748062D02*
Y754262D01*
G01X1493363Y748062D02*
X1496563D01*
G01X1493363Y754262D02*
Y748062D01*
G01X1508616Y739066D02*
X1505416D01*
G01X1517332Y811121D02*
G03I-9950J0D01*
G01X1502912Y1287905D02*
Y1299905D01*
G01X1496912Y1287905D02*
X1502912D01*
G01X1496912Y1299905D02*
Y1287905D01*
G01X1495021Y1281056D02*
Y1316752D01*
G01X1502912Y1299905D02*
X1496912D01*
G01X1493950Y1321346D02*
Y1333346D01*
G01X1496247Y1333406D02*
Y1321406D01*
G01X1502247D02*
Y1333406D01*
G01X1496247Y1321406D02*
X1502247D01*
G01X1494340Y1337378D02*
Y1349378D01*
G01X1502247Y1333406D02*
X1496247D01*
G01X1507964Y1350947D02*
X1511164D01*
G01X1507964Y1357147D02*
Y1350947D01*
G01X1511164Y1357147D02*
X1507964D01*
G01X1503470Y1356991D02*
X1506670D01*
G01X1503470Y1363191D02*
Y1356991D01*
G01X1506670Y1363191D02*
X1503470D01*
G01X1506670Y1356991D02*
Y1363191D01*
G01X1502626Y1666102D02*
Y1669202D01*
X1503086Y1668582D01*
G01Y1666102D02*
X1502166D01*
G01X1511228Y1668685D02*
X1510998Y1668995D01*
X1510730Y1669150D01*
X1510423Y1669202D01*
X1510040Y1669099D01*
X1509772Y1668840D01*
X1509695Y1668530D01*
X1509733Y1668220D01*
X1509887Y1667962D01*
X1510653Y1667445D01*
X1510998Y1667084D01*
X1511228Y1666567D01*
X1511305Y1666102D01*
X1509695D01*
G01X1498790Y1683643D02*
Y1680543D01*
X1497256D01*
G01X1499020Y1675819D02*
Y1678919D01*
X1498023Y1676336D01*
X1497026Y1678919D01*
Y1675819D01*
G01X1498905Y1671095D02*
Y1674195D01*
X1497141Y1671095D01*
Y1674195D01*
G01X1498483Y1697817D02*
X1497563D01*
G01X1498023D02*
Y1694717D01*
G01X1498483D02*
X1497563D01*
G01X1498790Y1690612D02*
X1498598Y1690302D01*
X1498368Y1690095D01*
X1498100Y1689992D01*
X1497793Y1690095D01*
X1497563Y1690302D01*
X1497333Y1690612D01*
X1497256Y1691025D01*
Y1693092D01*
G01X1498866Y1685268D02*
Y1688368D01*
G01X1497410D02*
X1498866Y1686456D01*
G01X1497180Y1685268D02*
X1498215Y1687335D01*
G01X1497256Y1713614D02*
X1498790D01*
Y1716714D01*
X1497256D01*
G01X1497870Y1715216D02*
X1498790D01*
G01X1498751Y1708890D02*
Y1711990D01*
X1497295D01*
G01X1497831Y1710492D02*
X1498751D01*
G01X1497687Y1705362D02*
X1496920D01*
Y1704432D01*
X1497150Y1704122D01*
X1497419Y1703915D01*
X1497802Y1703812D01*
X1498185Y1703915D01*
X1498454Y1704122D01*
X1498684Y1704432D01*
X1498837Y1704794D01*
X1498914Y1705207D01*
Y1705569D01*
X1498837Y1705879D01*
X1498684Y1706240D01*
X1498454Y1706550D01*
X1498224Y1706757D01*
X1497917Y1706912D01*
X1497649D01*
X1497342Y1706809D01*
X1497112Y1706602D01*
G01X1498822Y1699012D02*
Y1702112D01*
G01X1497212D02*
Y1699012D01*
G01Y1700562D02*
X1498822D01*
G01X1497716Y1729441D02*
X1497563Y1729596D01*
X1497448Y1729855D01*
X1497371Y1730216D01*
X1497448Y1730526D01*
X1497601Y1730733D01*
X1497870Y1730888D01*
X1498905D01*
Y1727788D01*
X1497640D01*
X1497371Y1727995D01*
X1497218Y1728305D01*
X1497141Y1728666D01*
X1497218Y1729028D01*
X1497448Y1729338D01*
X1497716Y1729441D01*
X1498905D01*
G01X1497180Y1725905D02*
X1497410Y1726060D01*
X1497678Y1726163D01*
X1497985D01*
X1498330Y1726008D01*
X1498598Y1725750D01*
X1498790Y1725440D01*
X1498943Y1724923D01*
X1498981Y1724458D01*
X1498905Y1723993D01*
X1498790Y1723683D01*
X1498560Y1723373D01*
X1498291Y1723166D01*
X1498023Y1723063D01*
X1497755D01*
X1497486Y1723166D01*
X1497256Y1723321D01*
X1497065Y1723528D01*
G01X1498866Y1718339D02*
Y1721439D01*
X1498100D01*
X1497793Y1721284D01*
X1497563Y1721077D01*
X1497371Y1720767D01*
X1497218Y1720406D01*
X1497180Y1719889D01*
X1497218Y1719372D01*
X1497371Y1719011D01*
X1497563Y1718701D01*
X1497793Y1718494D01*
X1498100Y1718339D01*
X1498866D01*
G01X1498775Y1733012D02*
X1497817Y1736112D01*
X1496859Y1733012D01*
G01X1497204Y1734097D02*
X1498430D01*
G01X1512037Y312225D02*
Y318425D01*
G01X1519400Y314312D02*
X1513200D01*
Y311112D01*
X1519400D01*
Y314312D01*
G01X1521457Y551557D02*
Y554657D01*
X1520460Y552074D01*
X1519463Y554657D01*
Y551557D01*
G01X1516593D02*
X1518127D01*
Y554657D01*
X1516593D01*
G01X1517207Y553159D02*
X1518127D01*
G01X1514260Y551557D02*
Y554657D01*
X1514720Y554037D01*
G01Y551557D02*
X1513800D01*
G01X1510700D02*
Y554657D01*
X1512118Y552435D01*
X1510202D01*
G01X1523575Y754365D02*
X1520375D01*
G01X1523575Y748165D02*
Y754365D01*
G01X1520375Y748165D02*
X1523575D01*
G01X1520375Y754365D02*
Y748165D01*
G01X1528785Y754365D02*
X1525585D01*
G01Y748165D02*
X1528785D01*
G01X1525585Y754365D02*
Y748165D01*
G01X1519175Y754365D02*
X1515975D01*
G01X1519175Y748165D02*
Y754365D01*
G01X1515975Y748165D02*
X1519175D01*
G01X1515975Y754365D02*
Y748165D01*
G01Y739830D02*
X1519175D01*
G01X1515975Y746030D02*
Y739830D01*
G01X1519175Y746030D02*
X1515975D01*
G01X1519175Y739830D02*
Y746030D01*
G01X1516718Y1299470D02*
Y1311470D01*
G01X1510718Y1299470D02*
X1516718D01*
G01X1510718Y1311470D02*
Y1299470D01*
G01X1523528Y1299520D02*
Y1311520D01*
G01X1517528Y1299520D02*
X1523528D01*
G01X1517528Y1311520D02*
Y1299520D01*
G01X1516718Y1311470D02*
X1510718D01*
G01X1523528Y1311520D02*
X1517528D01*
G01X1520078Y1356144D02*
Y1344144D01*
G01X1526078Y1356144D02*
X1520078D01*
G01Y1344144D02*
X1526078D01*
G01X1511164Y1350947D02*
Y1357147D01*
G01X1520468Y1359376D02*
X1526468D01*
G01X1520468Y1371376D02*
Y1359376D01*
G01X1526468Y1371376D02*
X1520468D01*
G01X1519217Y1666722D02*
X1518987Y1666360D01*
X1518681Y1666154D01*
X1518336Y1666102D01*
X1518029Y1666154D01*
X1517722Y1666412D01*
X1517531Y1666722D01*
X1517492Y1667032D01*
X1517569Y1667394D01*
X1517837Y1667652D01*
X1518106Y1667755D01*
X1518451D01*
G01X1518106D02*
X1517876Y1667910D01*
X1517684Y1668169D01*
X1517607Y1668479D01*
X1517684Y1668789D01*
X1517876Y1669047D01*
X1518221Y1669202D01*
X1518566Y1669150D01*
X1518911Y1668944D01*
G01X1525788Y1666102D02*
Y1669202D01*
X1527206Y1666980D01*
X1525290D01*
G01X1532400Y125262D02*
X1535600D01*
G01Y131462D02*
X1532400D01*
G01X1535600Y125262D02*
Y131462D01*
G01X1532400D02*
Y125262D01*
G01X1528785Y748165D02*
Y754365D01*
G01X1560659Y991220D02*
G03I-9950J0D01*
G01X1547008Y1333120D02*
X1535008D01*
G01Y1327120D02*
X1547008D01*
G01X1535008Y1333120D02*
Y1327120D01*
G01Y1335920D02*
X1547008D01*
G01X1535008Y1341920D02*
Y1335920D01*
G01X1526078Y1344144D02*
Y1356144D01*
G01X1547008Y1341920D02*
X1535008D01*
G01X1528456Y1356144D02*
Y1344144D01*
G01X1534456Y1356144D02*
X1528456D01*
G01X1534456Y1344144D02*
Y1356144D01*
G01X1528456Y1344144D02*
X1534456D01*
G01X1526468Y1359376D02*
Y1371376D01*
G01X1542724Y1667394D02*
X1542456Y1667755D01*
X1542226Y1667962D01*
X1541919Y1668065D01*
X1541651Y1667962D01*
X1541459Y1667755D01*
X1541306Y1667445D01*
X1541268Y1667084D01*
X1541306Y1666774D01*
X1541459Y1666464D01*
X1541689Y1666205D01*
X1541958Y1666102D01*
X1542264Y1666205D01*
X1542533Y1666515D01*
X1542686Y1666980D01*
X1542724Y1667497D01*
X1542648Y1668169D01*
X1542533Y1668530D01*
X1542341Y1668892D01*
X1542073Y1669150D01*
X1541804Y1669202D01*
X1541536Y1669099D01*
X1541344Y1668840D01*
G01X1534965Y1666567D02*
X1534735Y1666309D01*
X1534467Y1666154D01*
X1534122Y1666102D01*
X1533777Y1666205D01*
X1533509Y1666412D01*
X1533317Y1666774D01*
X1533279Y1667187D01*
X1533355Y1667600D01*
X1533547Y1667859D01*
X1533815Y1668065D01*
X1534084Y1668117D01*
X1534352Y1668065D01*
X1534697Y1667859D01*
X1534582Y1669202D01*
X1533547D01*
G01X1547008Y1327120D02*
Y1333120D01*
G01Y1335920D02*
Y1341920D01*
G01X1643307Y1646023D02*
X1553150D01*
G01D02*
Y1781456D01*
G01X1549947Y1666102D02*
X1549870Y1666774D01*
X1549755Y1667342D01*
X1549602Y1667859D01*
X1549410Y1668427D01*
X1549103Y1669202D01*
X1550637D01*
G01X1557744Y1666102D02*
X1557476Y1666154D01*
X1557169Y1666309D01*
X1556977Y1666567D01*
X1556901Y1666929D01*
X1556977Y1667290D01*
X1557207Y1667600D01*
X1557552Y1667755D01*
X1557936D01*
X1558166Y1667859D01*
X1558357Y1668117D01*
X1558434Y1668479D01*
X1558319Y1668840D01*
X1558051Y1669099D01*
X1557744Y1669202D01*
X1557437Y1669099D01*
X1557169Y1668840D01*
X1557054Y1668479D01*
X1557131Y1668117D01*
X1557322Y1667859D01*
X1557552Y1667755D01*
X1557936D01*
X1558281Y1667600D01*
X1558511Y1667290D01*
X1558587Y1666929D01*
X1558511Y1666567D01*
X1558319Y1666309D01*
X1558012Y1666154D01*
X1557744Y1666102D01*
G01X1553150Y1781456D02*
X1643307D01*
G01X1563490Y197152D02*
Y203352D01*
G01X1560290Y197152D02*
X1563490D01*
G01X1560290Y203352D02*
Y197152D01*
G01X1563490Y203352D02*
X1560290D01*
G01X1564490Y245022D02*
X1561290D01*
G01X1564490Y238822D02*
Y245022D01*
G01X1561290Y238822D02*
X1564490D01*
G01X1561290Y245022D02*
Y238822D01*
G01X1575107Y754185D02*
X1571907D01*
G01Y747985D02*
X1575107D01*
G01X1571907Y754185D02*
Y747985D01*
G01X1565569Y1682733D02*
Y1679633D01*
X1564035D01*
G01X1565799Y1674909D02*
Y1678009D01*
X1564802Y1675426D01*
X1563805Y1678009D01*
Y1674909D01*
G01X1565684Y1670185D02*
Y1673285D01*
X1563920Y1670185D01*
Y1673285D01*
G01X1571965Y1666702D02*
Y1669802D01*
X1572425Y1669182D01*
G01Y1666702D02*
X1571505D01*
G01X1565601Y1698102D02*
Y1701202D01*
G01X1563991D02*
Y1698102D01*
G01Y1699652D02*
X1565601D01*
G01X1565262Y1696907D02*
X1564342D01*
G01X1564802D02*
Y1693807D01*
G01X1565262D02*
X1564342D01*
G01X1565569Y1689702D02*
X1565377Y1689392D01*
X1565147Y1689185D01*
X1564879Y1689082D01*
X1564572Y1689185D01*
X1564342Y1689392D01*
X1564112Y1689702D01*
X1564035Y1690115D01*
Y1692182D01*
G01X1565645Y1684358D02*
Y1687458D01*
G01X1564189D02*
X1565645Y1685546D01*
G01X1563959Y1684358D02*
X1564994Y1686425D01*
G01X1564035Y1712704D02*
X1565569D01*
Y1715804D01*
X1564035D01*
G01X1564649Y1714306D02*
X1565569D01*
G01X1565530Y1707980D02*
Y1711080D01*
X1564074D01*
G01X1564610Y1709582D02*
X1565530D01*
G01X1564466Y1704452D02*
X1563699D01*
Y1703522D01*
X1563929Y1703212D01*
X1564198Y1703005D01*
X1564581Y1702902D01*
X1564964Y1703005D01*
X1565233Y1703212D01*
X1565463Y1703522D01*
X1565616Y1703884D01*
X1565693Y1704297D01*
Y1704659D01*
X1565616Y1704969D01*
X1565463Y1705330D01*
X1565233Y1705640D01*
X1565003Y1705847D01*
X1564696Y1706002D01*
X1564428D01*
X1564121Y1705899D01*
X1563891Y1705692D01*
G01X1564495Y1728531D02*
X1564342Y1728686D01*
X1564227Y1728945D01*
X1564150Y1729306D01*
X1564227Y1729616D01*
X1564380Y1729823D01*
X1564649Y1729978D01*
X1565684D01*
Y1726878D01*
X1564419D01*
X1564150Y1727085D01*
X1563997Y1727395D01*
X1563920Y1727756D01*
X1563997Y1728118D01*
X1564227Y1728428D01*
X1564495Y1728531D01*
X1565684D01*
G01X1563959Y1724995D02*
X1564189Y1725150D01*
X1564457Y1725253D01*
X1564764D01*
X1565109Y1725098D01*
X1565377Y1724840D01*
X1565569Y1724530D01*
X1565722Y1724013D01*
X1565760Y1723548D01*
X1565684Y1723083D01*
X1565569Y1722773D01*
X1565339Y1722463D01*
X1565070Y1722256D01*
X1564802Y1722153D01*
X1564534D01*
X1564265Y1722256D01*
X1564035Y1722411D01*
X1563844Y1722618D01*
G01X1565645Y1717429D02*
Y1720529D01*
X1564879D01*
X1564572Y1720374D01*
X1564342Y1720167D01*
X1564150Y1719857D01*
X1563997Y1719496D01*
X1563959Y1718979D01*
X1563997Y1718462D01*
X1564150Y1718101D01*
X1564342Y1717791D01*
X1564572Y1717584D01*
X1564879Y1717429D01*
X1565645D01*
G01X1565554Y1732102D02*
X1564596Y1735202D01*
X1563638Y1732102D01*
G01X1563983Y1733187D02*
X1565209D01*
G01X1587498Y217168D02*
Y213968D01*
G01X1593698Y217168D02*
X1587498D01*
G01Y213968D02*
X1593698D01*
G01X1587478Y209926D02*
X1593678D01*
G01X1587478Y213126D02*
Y209926D01*
G01X1593678Y213126D02*
X1587478D01*
G01Y209167D02*
Y205967D01*
G01X1593678Y209167D02*
X1587478D01*
G01Y205967D02*
X1593678D01*
G01X1587462Y229890D02*
X1593662D01*
G01X1587462Y233090D02*
Y229890D01*
G01X1593662Y233090D02*
X1587462D01*
G01Y237582D02*
Y234382D01*
G01X1593662Y237582D02*
X1587462D01*
G01Y234382D02*
X1593662D01*
G01X1593711Y604266D02*
Y602026D01*
G01X1592086Y603239D02*
X1595336D01*
G01X1588663Y638075D02*
X1590903D01*
G01X1589690Y636450D02*
Y639700D01*
G01X1588663Y672075D02*
X1590903D01*
G01X1589690Y670450D02*
Y673700D01*
G01X1588663Y706075D02*
X1590903D01*
G01X1589690Y704450D02*
Y707700D01*
G01X1582400Y748262D02*
X1585600D01*
G01X1582400Y754462D02*
Y748262D01*
G01X1585600D02*
Y754462D01*
G01X1575107Y747985D02*
Y754185D01*
G01X1579107D02*
X1575907D01*
G01X1579107Y747985D02*
Y754185D01*
G01X1575907Y747985D02*
X1579107D01*
G01X1575907Y754185D02*
Y747985D01*
G01X1580400Y755262D02*
X1583600D01*
G01X1580400Y761462D02*
Y755262D01*
G01X1583600Y761462D02*
X1580400D01*
G01X1583600Y755262D02*
Y761462D01*
G01X1585600Y754462D02*
X1582400D01*
G01X1589315Y756945D02*
X1592515D01*
G01X1589315Y763145D02*
Y756945D01*
G01X1592515Y763145D02*
X1589315D01*
G01X1592515Y770305D02*
X1589315D01*
G01Y764105D02*
X1592515D01*
G01X1589315Y770305D02*
Y764105D01*
G01X1580417Y898965D02*
X1583617D01*
G01X1580417Y905165D02*
Y898965D01*
G01X1583617D02*
Y905165D01*
G01Y897683D02*
X1580417D01*
G01X1583617Y891483D02*
Y897683D01*
G01X1580417Y891483D02*
X1583617D01*
G01X1580417Y897683D02*
Y891483D01*
G01X1583617Y912345D02*
X1580417D01*
G01X1583617Y906145D02*
Y912345D01*
G01X1580417Y906145D02*
X1583617D01*
G01X1580417Y912345D02*
Y906145D01*
G01X1583617Y905165D02*
X1580417D01*
G01X1576378Y1663900D02*
Y1646023D01*
G01X1641167Y1654032D02*
Y1661532D01*
X1638927D01*
X1638180Y1661157D01*
X1637620Y1660282D01*
X1637433Y1659282D01*
X1637620Y1658282D01*
X1638087Y1657532D01*
X1638927Y1657157D01*
X1641167D01*
G01X1633667Y1654032D02*
Y1661532D01*
X1631333D01*
X1630587Y1661157D01*
X1630120Y1660657D01*
X1629933Y1659657D01*
X1630120Y1658657D01*
X1630680Y1658032D01*
X1631333Y1657657D01*
X1633667D01*
G01X1631333D02*
X1629933Y1654032D01*
G01X1622433D02*
X1626167D01*
Y1661532D01*
X1622433D01*
G01X1623927Y1657907D02*
X1626167D01*
G01X1618760Y1655032D02*
X1618013Y1654407D01*
X1617173Y1654032D01*
X1616427D01*
X1615680Y1654407D01*
X1615120Y1655032D01*
X1614840Y1655907D01*
X1615027Y1656782D01*
X1615493Y1657532D01*
X1616333Y1658032D01*
X1617453Y1658282D01*
X1618107Y1658782D01*
X1618387Y1659657D01*
X1618200Y1660532D01*
X1617733Y1661157D01*
X1617080Y1661532D01*
X1616427D01*
X1615773Y1661282D01*
X1615213Y1660657D01*
G01X1611260Y1655032D02*
X1610513Y1654407D01*
X1609673Y1654032D01*
X1608927D01*
X1608180Y1654407D01*
X1607620Y1655032D01*
X1607340Y1655907D01*
X1607527Y1656782D01*
X1607993Y1657532D01*
X1608833Y1658032D01*
X1609953Y1658282D01*
X1610607Y1658782D01*
X1610887Y1659657D01*
X1610700Y1660532D01*
X1610233Y1661157D01*
X1609580Y1661532D01*
X1608927D01*
X1608273Y1661282D01*
X1607713Y1660657D01*
G01X1603013Y1656532D02*
X1600587D01*
G01X1596073Y1654032D02*
Y1661532D01*
X1592527D01*
G01X1593833Y1657907D02*
X1596073D01*
G01X1587920Y1661532D02*
X1585680D01*
G01X1586800D02*
Y1654032D01*
G01X1587920D02*
X1585680D01*
G01X1579300Y1661532D02*
Y1654032D01*
G01X1581447Y1661532D02*
X1577153D01*
G01X1580567Y1669285D02*
X1580337Y1669595D01*
X1580069Y1669750D01*
X1579762Y1669802D01*
X1579379Y1669699D01*
X1579111Y1669440D01*
X1579034Y1669130D01*
X1579072Y1668820D01*
X1579226Y1668562D01*
X1579992Y1668045D01*
X1580337Y1667684D01*
X1580567Y1667167D01*
X1580644Y1666702D01*
X1579034D01*
G01X1588556Y1667322D02*
X1588326Y1666960D01*
X1588020Y1666754D01*
X1587675Y1666702D01*
X1587368Y1666754D01*
X1587061Y1667012D01*
X1586870Y1667322D01*
X1586831Y1667632D01*
X1586908Y1667994D01*
X1587176Y1668252D01*
X1587445Y1668355D01*
X1587790D01*
G01X1587445D02*
X1587215Y1668510D01*
X1587023Y1668769D01*
X1586946Y1669079D01*
X1587023Y1669389D01*
X1587215Y1669647D01*
X1587560Y1669802D01*
X1587905Y1669750D01*
X1588250Y1669544D01*
G01X1576378Y1781456D02*
Y1736830D01*
G01X1593698Y213968D02*
Y217168D01*
G01X1593678Y209926D02*
Y213126D01*
G01Y205967D02*
Y209167D01*
G01X1593662Y229890D02*
Y233090D01*
G01Y234382D02*
Y237582D01*
G01X1605455Y586185D02*
X1617455D01*
G01X1605455Y592185D02*
Y586185D01*
G01X1617455Y592185D02*
X1605455D01*
G01X1599879Y611801D02*
Y594085D01*
G01D02*
X1635575D01*
G01X1605455Y613701D02*
X1617455D01*
G01X1605455Y619701D02*
Y613701D01*
G01X1617455Y619701D02*
X1605455D01*
G01X1599955Y621862D02*
X1611955D01*
G01X1599955Y627862D02*
Y621862D01*
G01X1635575Y611801D02*
X1599879D01*
G01X1611955Y627862D02*
X1599955D01*
G01X1593488Y630060D02*
X1593485Y647000D01*
G01X1592888Y630060D02*
X1592884Y647035D01*
G01X1592288Y630060D02*
X1592294Y647043D01*
G01X1592288Y630060D02*
X1593488D01*
G01Y646992D02*
Y630062D01*
G01D02*
X1629228D01*
G01X1599955Y655862D02*
X1611955D01*
G01X1599955Y661862D02*
Y655862D01*
G01Y648592D02*
X1611955D01*
G01X1599955Y654592D02*
Y648592D01*
G01X1611955Y654592D02*
X1599955D01*
G01X1592338Y646993D02*
X1593847Y646989D01*
G01X1629228Y646992D02*
X1593488D01*
G01X1611955Y661862D02*
X1599955D01*
G01X1593488Y664060D02*
X1593485Y681000D01*
G01X1592888Y664060D02*
X1592884Y681035D01*
G01X1592288Y664060D02*
X1592294Y681043D01*
G01X1592288Y664060D02*
X1593488D01*
G01Y680992D02*
Y664062D01*
G01D02*
X1629228D01*
G01X1599955Y682592D02*
X1611955D01*
G01X1599955Y688592D02*
Y682592D01*
G01X1611955Y688592D02*
X1599955D01*
G01X1592338Y680993D02*
X1593847Y680989D01*
G01X1629228Y680992D02*
X1593488D01*
G01X1599955Y689862D02*
X1611955D01*
G01X1599955Y695862D02*
Y689862D01*
G01X1611955Y695862D02*
X1599955D01*
G01X1593488Y698060D02*
X1593485Y715000D01*
G01X1592888Y698060D02*
X1592884Y715035D01*
G01X1592288Y698060D02*
X1592294Y715043D01*
G01X1592288Y698060D02*
X1593488D01*
G01Y714992D02*
Y698062D01*
G01D02*
X1629228D01*
G01X1599955Y716592D02*
X1611955D01*
G01X1599955Y722592D02*
Y716592D01*
G01X1592338Y714993D02*
X1593847Y714989D01*
G01X1629228Y714992D02*
X1593488D01*
G01X1611955Y722592D02*
X1599955D01*
G01X1602820Y726662D02*
Y723462D01*
G01X1609020Y726662D02*
X1602820D01*
G01Y723462D02*
X1609020D01*
G01X1601188Y757095D02*
X1604388D01*
G01X1601188Y763295D02*
Y757095D01*
G01X1604388Y763295D02*
X1601188D01*
G01X1604388Y757095D02*
Y763295D01*
G01X1592515Y756945D02*
Y763145D01*
G01X1593397Y756915D02*
X1596597D01*
G01X1593397Y763115D02*
Y756915D01*
G01X1596597Y763115D02*
X1593397D01*
G01X1596597Y756915D02*
Y763115D01*
G01X1592515Y764105D02*
Y770305D01*
G01X1605188Y757095D02*
X1608388D01*
G01X1605188Y763295D02*
Y757095D01*
G01X1608388Y763295D02*
X1605188D01*
G01X1598397Y993225D02*
Y981225D01*
G01X1604397D02*
Y993225D01*
G01X1598397Y981225D02*
X1604397D01*
G01Y993225D02*
X1598397D01*
G01X1606477Y1011001D02*
X1612477D01*
G01X1606477Y1023001D02*
Y1011001D01*
G01X1604482Y1009315D02*
Y1021315D01*
G01X1598482Y1009315D02*
X1604482D01*
G01X1598482Y1021315D02*
Y1009315D01*
G01X1612477Y1023001D02*
X1606477D01*
G01X1604482Y1021315D02*
X1598482D01*
G01X1604250Y1253123D02*
Y1259323D01*
G01X1601050Y1253123D02*
X1604250D01*
G01X1601050Y1259323D02*
Y1253123D01*
G01X1604250Y1252120D02*
X1601050D01*
G01X1604250Y1245920D02*
Y1252120D01*
G01X1601050Y1245920D02*
X1604250D01*
G01X1601050Y1252120D02*
Y1245920D01*
G01X1604441Y1259944D02*
Y1271944D01*
G01X1598441Y1259944D02*
X1604441D01*
G01X1598441Y1271944D02*
Y1259944D01*
G01X1604441Y1271944D02*
X1598441D01*
G01X1604250Y1259323D02*
X1601050D01*
G01X1595127Y1666702D02*
Y1669802D01*
X1596545Y1667580D01*
X1594629D01*
G01X1604304Y1667167D02*
X1604074Y1666909D01*
X1603806Y1666754D01*
X1603461Y1666702D01*
X1603116Y1666805D01*
X1602848Y1667012D01*
X1602656Y1667374D01*
X1602618Y1667787D01*
X1602694Y1668200D01*
X1602886Y1668459D01*
X1603154Y1668665D01*
X1603423Y1668717D01*
X1603691Y1668665D01*
X1604036Y1668459D01*
X1603921Y1669802D01*
X1602886D01*
G01X1617455Y586185D02*
Y592185D01*
G01X1608420Y584962D02*
Y581762D01*
G01X1614620Y584962D02*
X1608420D01*
G01X1614620Y581762D02*
Y584962D01*
G01X1608420Y581762D02*
X1614620D01*
G01X1617455Y613701D02*
Y619701D01*
G01X1611955Y621862D02*
Y627862D01*
G01Y655862D02*
Y661862D01*
G01Y648592D02*
Y654592D01*
G01Y682592D02*
Y688592D01*
G01Y689862D02*
Y695862D01*
G01Y716592D02*
Y722592D01*
G01X1609020Y723462D02*
Y726662D01*
G01X1617188Y757095D02*
X1620388D01*
G01X1617188Y763295D02*
Y757095D01*
G01X1620388Y763295D02*
X1617188D01*
G01X1620388Y757095D02*
Y763295D01*
G01X1608388Y757095D02*
Y763295D01*
G01X1609188Y757095D02*
X1612388D01*
G01X1609188Y763295D02*
Y757095D01*
G01X1612388Y763295D02*
X1609188D01*
G01X1612388Y757095D02*
Y763295D01*
G01X1613188Y757095D02*
X1616388D01*
G01X1613188Y763295D02*
Y757095D01*
G01X1616388Y763295D02*
X1613188D01*
G01X1616388Y757095D02*
Y763295D01*
G01X1614526Y993367D02*
Y981367D01*
G01X1620526D02*
Y993367D01*
G01X1614526Y981367D02*
X1620526D01*
G01Y993367D02*
X1614526D01*
G01X1621206Y1004379D02*
X1627206D01*
G01X1621206Y1016379D02*
Y1004379D01*
G01X1620386Y1010566D02*
Y1022566D01*
G01X1614386Y1010566D02*
X1620386D01*
G01X1614386Y1022566D02*
Y1010566D01*
G01X1612477Y1011001D02*
Y1023001D01*
G01X1627206Y1016379D02*
X1621206D01*
G01X1620386Y1022566D02*
X1614386D01*
G01X1617714Y1258644D02*
X1614514D01*
G01X1617714Y1252444D02*
Y1258644D01*
G01X1614514Y1252444D02*
X1617714D01*
G01X1614514Y1258644D02*
Y1252444D01*
G01X1614114Y1253344D02*
Y1256544D01*
G01X1607914Y1253344D02*
X1614114D01*
G01X1607914Y1256544D02*
Y1253344D01*
G01X1614114Y1256544D02*
X1607914D01*
G01X1620441Y1259944D02*
Y1271944D01*
G01X1614441Y1259944D02*
X1620441D01*
G01X1614441Y1271944D02*
Y1259944D01*
G01X1620441Y1271944D02*
X1614441D01*
G01X1621454Y1384785D02*
X1627454D01*
G01X1621454Y1396785D02*
Y1384785D01*
G01X1627454Y1396785D02*
X1621454D01*
G01X1620477Y1435416D02*
X1623677D01*
G01X1620477Y1441616D02*
Y1435416D01*
G01X1623677Y1441616D02*
X1620477D01*
G01X1612063Y1667994D02*
X1611795Y1668355D01*
X1611565Y1668562D01*
X1611258Y1668665D01*
X1610990Y1668562D01*
X1610798Y1668355D01*
X1610645Y1668045D01*
X1610607Y1667684D01*
X1610645Y1667374D01*
X1610798Y1667064D01*
X1611028Y1666805D01*
X1611297Y1666702D01*
X1611603Y1666805D01*
X1611872Y1667115D01*
X1612025Y1667580D01*
X1612063Y1668097D01*
X1611987Y1668769D01*
X1611872Y1669130D01*
X1611680Y1669492D01*
X1611412Y1669750D01*
X1611143Y1669802D01*
X1610875Y1669699D01*
X1610683Y1669440D01*
G01X1619286Y1666702D02*
X1619209Y1667374D01*
X1619094Y1667942D01*
X1618941Y1668459D01*
X1618749Y1669027D01*
X1618442Y1669802D01*
X1619976D01*
G01X1643827Y174699D02*
Y177799D01*
X1642830Y175216D01*
X1641833Y177799D01*
Y174699D01*
G01X1638963D02*
X1640497D01*
Y177799D01*
X1638963D01*
G01X1639577Y176301D02*
X1640497D01*
G01X1636170Y174699D02*
Y177799D01*
X1637588Y175577D01*
X1635672D01*
G01X1638414Y603243D02*
X1640840D01*
G01X1635575Y594085D02*
Y611801D01*
G01X1631910Y622705D02*
X1643910D01*
G01X1631910Y628705D02*
Y622705D01*
G01X1643910Y637111D02*
X1631910D01*
G01Y631111D02*
X1643910D01*
G01X1631910Y637111D02*
Y631111D01*
G01X1643910Y628705D02*
X1631910D01*
G01X1635177Y643282D02*
X1637603D01*
G01X1629228Y630062D02*
Y646992D01*
G01X1631910Y656705D02*
X1643910D01*
G01X1631910Y662705D02*
Y656705D01*
G01X1638619Y649563D02*
Y646363D01*
G01X1644819Y649563D02*
X1638619D01*
G01Y646363D02*
X1644819D01*
G01X1643910Y671111D02*
X1631910D01*
G01Y665111D02*
X1643910D01*
G01X1631910Y671111D02*
Y665111D01*
G01X1643910Y662705D02*
X1631910D01*
G01X1635397Y677292D02*
X1637823D01*
G01X1629228Y664062D02*
Y680992D01*
G01X1638619Y683563D02*
Y680363D01*
G01X1644819Y683563D02*
X1638619D01*
G01Y680363D02*
X1644819D01*
G01X1643910Y696705D02*
X1631910D01*
G01Y690705D02*
X1643910D01*
G01X1631910Y696705D02*
Y690705D01*
G01X1643910Y705111D02*
X1631910D01*
G01Y699111D02*
X1643910D01*
G01X1631910Y705111D02*
Y699111D01*
G01X1629228Y698062D02*
Y714992D01*
G01X1633117Y710912D02*
X1635543D01*
G01X1638619Y717563D02*
Y714363D01*
G01X1644819Y717563D02*
X1638619D01*
G01Y714363D02*
X1644819D01*
G01X1637328Y757095D02*
X1640528D01*
G01X1637328Y763295D02*
Y757095D01*
G01X1640528Y763295D02*
X1637328D01*
G01X1629328Y757095D02*
X1632528D01*
G01X1629328Y763295D02*
Y757095D01*
G01X1632528Y763295D02*
X1629328D01*
G01X1632528Y757095D02*
Y763295D01*
G01X1633328Y757095D02*
X1636528D01*
G01X1633328Y763295D02*
Y757095D01*
G01X1636528Y763295D02*
X1633328D01*
G01X1636528Y757095D02*
Y763295D01*
G01X1627206Y1004379D02*
Y1016379D01*
G01X1628041Y1258544D02*
Y1255344D01*
G01X1634241Y1258544D02*
X1628041D01*
G01X1634241Y1255344D02*
Y1258544D01*
G01X1628041Y1255344D02*
X1634241D01*
G01X1635014Y1253244D02*
X1641214D01*
G01X1635014Y1256444D02*
Y1253244D01*
G01X1641214Y1256444D02*
X1635014D01*
G01X1633145Y1249643D02*
X1629945D01*
G01X1633145Y1243443D02*
Y1249643D01*
G01X1629945Y1243443D02*
X1633145D01*
G01X1629945Y1249643D02*
Y1243443D01*
G01X1634141Y1259944D02*
Y1271944D01*
G01X1628141Y1259944D02*
X1634141D01*
G01X1628141Y1271944D02*
Y1259944D01*
G01X1634141Y1271944D02*
X1628141D01*
G01X1636950Y1373243D02*
X1639190D01*
G01X1637977Y1371618D02*
Y1374868D01*
G01X1627454Y1384785D02*
Y1396785D01*
G01X1629415Y1379411D02*
X1647131D01*
G01X1629415Y1415107D02*
Y1379411D01*
G01X1630120Y1416949D02*
Y1419375D01*
G01X1647131Y1415107D02*
X1629415D01*
G01X1623677Y1435416D02*
Y1441616D01*
G01X1627000Y1426527D02*
X1630200D01*
G01X1627000Y1432727D02*
Y1426527D01*
G01X1630200Y1432727D02*
X1627000D01*
G01X1630200Y1426527D02*
Y1432727D01*
G01X1627083Y1666702D02*
X1626815Y1666754D01*
X1626508Y1666909D01*
X1626316Y1667167D01*
X1626240Y1667529D01*
X1626316Y1667890D01*
X1626546Y1668200D01*
X1626891Y1668355D01*
X1627275D01*
X1627505Y1668459D01*
X1627696Y1668717D01*
X1627773Y1669079D01*
X1627658Y1669440D01*
X1627390Y1669699D01*
X1627083Y1669802D01*
X1626776Y1669699D01*
X1626508Y1669440D01*
X1626393Y1669079D01*
X1626470Y1668717D01*
X1626661Y1668459D01*
X1626891Y1668355D01*
X1627275D01*
X1627620Y1668200D01*
X1627850Y1667890D01*
X1627926Y1667529D01*
X1627850Y1667167D01*
X1627658Y1666909D01*
X1627351Y1666754D01*
X1627083Y1666702D01*
G01X1653193Y520576D02*
X1659393D01*
G01X1653193Y523776D02*
Y520576D01*
G01X1659393Y523776D02*
X1653193D01*
G01X1653129Y538471D02*
X1659329D01*
G01X1653129Y541671D02*
Y538471D01*
G01X1659329Y541671D02*
X1653129D01*
G01Y537671D02*
Y534471D01*
G01X1659329Y537671D02*
X1653129D01*
G01Y534471D02*
X1659329D01*
G01X1653129Y533671D02*
Y530471D01*
G01X1659329Y533671D02*
X1653129D01*
G01Y530471D02*
X1659329D01*
G01X1653129Y546222D02*
Y543022D01*
G01X1659329Y546222D02*
X1653129D01*
G01Y543022D02*
X1659329D01*
G01X1653935Y587356D02*
Y593356D01*
G01X1641935Y587356D02*
X1653935D01*
G01X1641935Y593356D02*
Y587356D01*
G01X1653935Y593356D02*
X1641935D01*
G01X1643910Y622705D02*
Y628705D01*
G01X1651620Y613562D02*
X1654820D01*
G01X1651620Y619762D02*
Y613562D01*
G01X1654820Y619762D02*
X1651620D01*
G01X1654820Y613562D02*
Y619762D01*
G01X1643910Y631111D02*
Y637111D01*
G01Y656705D02*
Y662705D01*
G01X1644819Y646363D02*
Y649563D01*
G01X1644698Y655341D02*
Y652141D01*
G01X1650898Y655341D02*
X1644698D01*
G01X1650898Y652141D02*
Y655341D01*
G01X1644698Y652141D02*
X1650898D01*
G01X1643910Y665111D02*
Y671111D01*
G01X1644819Y680363D02*
Y683563D01*
G01X1644698Y689342D02*
Y686142D01*
G01X1650898D02*
Y689342D01*
G01X1644698Y686142D02*
X1650898D01*
G01X1643910Y690705D02*
Y696705D01*
G01Y699111D02*
Y705111D01*
G01X1650898Y689342D02*
X1644698D01*
G01X1644816Y723361D02*
Y720161D01*
G01X1651016D02*
Y723361D01*
G01X1644816Y720161D02*
X1651016D01*
G01X1644819Y714363D02*
Y717563D01*
G01X1651016Y723361D02*
X1644816D01*
G01X1640528Y757095D02*
Y763295D01*
G01X1653067Y758134D02*
X1656267D01*
G01X1653067Y764334D02*
Y758134D01*
G01X1656267Y764334D02*
X1653067D01*
G01X1644126Y1259092D02*
Y1255892D01*
G01X1650326D02*
Y1259092D01*
G01X1644126Y1255892D02*
X1650326D01*
G01X1641214Y1253244D02*
Y1256444D01*
G01X1655743Y1255285D02*
X1652543D01*
G01X1655743Y1249085D02*
Y1255285D01*
G01X1652543Y1249085D02*
X1655743D01*
G01X1652543Y1255285D02*
Y1249085D01*
G01X1650141Y1259944D02*
Y1271944D01*
G01X1644141Y1259944D02*
X1650141D01*
G01X1644141Y1271944D02*
Y1259944D01*
G01X1650141Y1271944D02*
X1644141D01*
G01X1650326Y1259092D02*
X1644126D01*
G01X1654992Y1384785D02*
Y1396785D01*
G01X1648992Y1384785D02*
X1654992D01*
G01X1648992Y1396785D02*
Y1384785D01*
G01X1647131Y1379411D02*
Y1415107D01*
G01X1654992Y1396785D02*
X1648992D01*
G01X1648249Y1431619D02*
Y1419619D01*
G01X1654249D02*
Y1431619D01*
G01X1648249Y1419619D02*
X1654249D01*
G01X1639843Y1431619D02*
Y1419619D01*
G01X1645843D02*
Y1431619D01*
G01X1639843Y1419619D02*
X1645843D01*
G01X1654249Y1431619D02*
X1648249D01*
G01X1645843D02*
X1639843D01*
G01X1649328Y1439736D02*
X1661328D01*
G01X1649328Y1445736D02*
Y1439736D01*
G01X1661328Y1445736D02*
X1649328D01*
G01X1643307Y1781456D02*
Y1646023D01*
G01X1659393Y520576D02*
Y523776D01*
G01X1671633Y538080D02*
Y541280D01*
G01X1665433D02*
Y538080D01*
G01X1671633Y541280D02*
X1665433D01*
G01Y538080D02*
X1671633D01*
G01X1671147Y532924D02*
Y536124D01*
G01X1664947D02*
Y532924D01*
G01X1671147Y536124D02*
X1664947D01*
G01Y532924D02*
X1671147D01*
G01X1660676Y538861D02*
X1663876D01*
G01X1660676Y545061D02*
Y538861D01*
G01X1663876D02*
Y545061D01*
G01X1659329Y538471D02*
Y541671D01*
G01Y534471D02*
Y537671D01*
G01Y530471D02*
Y533671D01*
G01X1671603Y526735D02*
Y529935D01*
G01X1665403D02*
Y526735D01*
G01X1671603Y529935D02*
X1665403D01*
G01Y526735D02*
X1671603D01*
G01X1663876Y545061D02*
X1660676D01*
G01X1659329Y543022D02*
Y546222D01*
G01X1666550Y605732D02*
Y608932D01*
G01X1660350Y605732D02*
X1666550D01*
G01X1660350Y608932D02*
Y605732D01*
G01X1666550Y608932D02*
X1660350D01*
G01X1662720Y618762D02*
X1659520D01*
G01X1662720Y612562D02*
Y618762D01*
G01X1659520Y612562D02*
X1662720D01*
G01X1659520Y618762D02*
Y612562D01*
G01X1657079Y758134D02*
X1660279D01*
G01X1657079Y764334D02*
Y758134D01*
G01X1660279Y764334D02*
X1657079D01*
G01X1660279Y758134D02*
Y764334D01*
G01X1665086Y758134D02*
X1668286D01*
G01X1665086Y764334D02*
Y758134D01*
G01X1668286Y764334D02*
X1665086D01*
G01X1668286Y758134D02*
Y764334D01*
G01X1661056Y758134D02*
X1664256D01*
G01X1661056Y764334D02*
Y758134D01*
G01X1664256Y764334D02*
X1661056D01*
G01X1664256Y758134D02*
Y764334D01*
G01X1656267Y758134D02*
Y764334D01*
G01X1657741Y1258544D02*
Y1255344D01*
G01X1663941Y1258544D02*
X1657741D01*
G01X1663941Y1255344D02*
Y1258544D01*
G01X1657741Y1255344D02*
X1663941D01*
G01X1671014Y1253444D02*
Y1256644D01*
G01X1664814Y1253444D02*
X1671014D01*
G01X1664814Y1256644D02*
Y1253444D01*
G01X1671014Y1256644D02*
X1664814D01*
G01X1663841Y1259944D02*
Y1271944D01*
G01X1657841Y1259944D02*
X1663841D01*
G01X1657841Y1271944D02*
Y1259944D01*
G01X1663841Y1271944D02*
X1657841D01*
G01X1666405Y1384785D02*
Y1396785D01*
G01X1660405Y1384785D02*
X1666405D01*
G01X1660405Y1396785D02*
Y1384785D01*
G01X1668312Y1379411D02*
X1686028D01*
G01X1668312Y1415107D02*
Y1379411D01*
G01X1656426Y1387126D02*
X1659626D01*
G01X1656426Y1393326D02*
Y1387126D01*
G01X1659626D02*
Y1393326D01*
G01X1666405Y1396785D02*
X1660405D01*
G01X1659626Y1393326D02*
X1656426D01*
G01X1669330Y1417189D02*
Y1419615D01*
G01X1686028Y1415107D02*
X1668312D01*
G01X1663517Y1426422D02*
X1666717D01*
G01X1663517Y1432622D02*
Y1426422D01*
G01X1666717Y1432622D02*
X1663517D01*
G01X1666717Y1426422D02*
Y1432622D01*
G01X1661328Y1439736D02*
Y1445736D01*
G01X1667266Y1445881D02*
X1664066D01*
G01Y1439681D02*
X1667266D01*
G01X1664066Y1445881D02*
Y1439681D01*
G01X1667266D02*
Y1445881D01*
G01X1680560Y106662D02*
Y109762D01*
X1681020Y109142D01*
G01Y106662D02*
X1680100D01*
G01X1678303Y107282D02*
X1678073Y106920D01*
X1677767Y106714D01*
X1677422Y106662D01*
X1677115Y106714D01*
X1676808Y106972D01*
X1676617Y107282D01*
X1676578Y107592D01*
X1676655Y107954D01*
X1676923Y108212D01*
X1677192Y108315D01*
X1677537D01*
G01X1677192D02*
X1676962Y108470D01*
X1676770Y108729D01*
X1676693Y109039D01*
X1676770Y109349D01*
X1676962Y109607D01*
X1677307Y109762D01*
X1677652Y109710D01*
X1677997Y109504D01*
G01X1678600Y183332D02*
Y186432D01*
X1679060Y185812D01*
G01Y183332D02*
X1678140D01*
G01X1687286Y477553D02*
Y483753D01*
G01X1684086Y477553D02*
X1687286D01*
G01X1684086Y483753D02*
Y477553D01*
G01X1684577Y465350D02*
X1690777D01*
G01X1684577Y468550D02*
Y465350D01*
G01X1690777Y468550D02*
X1684577D01*
G01X1677578Y480678D02*
Y477478D01*
G01X1683778D02*
Y480678D01*
G01X1677578Y477478D02*
X1683778D01*
G01X1687286Y483753D02*
X1684086D01*
G01X1686038Y486688D02*
Y489888D01*
G01X1679838Y486688D02*
X1686038D01*
G01X1679838Y489888D02*
Y486688D01*
G01X1686038Y489888D02*
X1679838D01*
G01X1683778Y480678D02*
X1677578D01*
G01Y484190D02*
Y480990D01*
G01X1683778Y484190D02*
X1677578D01*
G01X1683778Y480990D02*
Y484190D01*
G01X1677578Y480990D02*
X1683778D01*
G01X1683569Y500679D02*
X1689769D01*
G01X1683569Y503879D02*
Y500679D01*
G01X1689769Y503879D02*
X1683569D01*
G01X1695693Y1237362D02*
Y1240462D01*
X1694927D01*
X1694620Y1240307D01*
X1694390Y1240100D01*
X1694198Y1239790D01*
X1694045Y1239429D01*
X1694007Y1238912D01*
X1694045Y1238395D01*
X1694198Y1238034D01*
X1694390Y1237724D01*
X1694620Y1237517D01*
X1694927Y1237362D01*
X1695693D01*
G01X1691290D02*
Y1240462D01*
X1692708Y1238240D01*
X1690792D01*
G01X1688190Y1237362D02*
Y1240462D01*
X1689608Y1238240D01*
X1687692D01*
G01X1691500Y1236089D02*
Y1233849D01*
G01X1689875Y1235062D02*
X1693125D01*
G01X1687441Y1258544D02*
Y1255344D01*
G01X1693641Y1258544D02*
X1687441D01*
G01Y1255344D02*
X1693641D01*
G01X1677014Y1258644D02*
X1673814D01*
G01X1677014Y1252444D02*
Y1258644D01*
G01X1673814Y1252444D02*
X1677014D01*
G01X1673814Y1258644D02*
Y1252444D01*
G01X1687541Y1259944D02*
X1693541D01*
G01X1687541Y1271944D02*
Y1259944D01*
G01X1693541Y1271944D02*
X1687541D01*
G01X1679841Y1259944D02*
Y1271944D01*
G01X1673841Y1259944D02*
X1679841D01*
G01X1673841Y1271944D02*
Y1259944D01*
G01X1679841Y1271944D02*
X1673841D01*
G01X1675847Y1373243D02*
X1678087D01*
G01X1676874Y1371618D02*
Y1374868D01*
G01X1686028Y1379411D02*
Y1415107D01*
G01X1687965Y1386865D02*
X1691165D01*
G01X1687965Y1393065D02*
Y1386865D01*
G01X1691165Y1393065D02*
X1687965D01*
G01X1677986Y1431619D02*
Y1419619D01*
G01X1683986D02*
Y1431619D01*
G01X1677986Y1419619D02*
X1683986D01*
G01X1686392Y1431619D02*
Y1419619D01*
G01D02*
X1692392D01*
G01X1683986Y1431619D02*
X1677986D01*
G01X1692392D02*
X1686392D01*
G01X1701400Y91762D02*
X1704600D01*
G01X1701400Y97962D02*
Y91762D01*
G01X1704600Y97962D02*
X1701400D01*
G01X1704600Y91762D02*
Y97962D01*
G01X1697400Y91762D02*
X1700600D01*
G01X1697400Y97962D02*
Y91762D01*
G01X1700600Y97962D02*
X1697400D01*
G01X1700600Y91762D02*
Y97962D01*
G01X1695320Y106362D02*
Y109462D01*
X1695780Y108842D01*
G01Y106362D02*
X1694860D01*
G01X1691760D02*
Y109462D01*
X1693178Y107240D01*
X1691262D01*
G01X1692438Y184555D02*
X1692208Y184865D01*
X1691940Y185020D01*
X1691633Y185072D01*
X1691250Y184969D01*
X1690982Y184710D01*
X1690905Y184400D01*
X1690943Y184090D01*
X1691097Y183832D01*
X1691863Y183315D01*
X1692208Y182954D01*
X1692438Y182437D01*
X1692515Y181972D01*
X1690905D01*
G01X1693050Y200870D02*
X1699250D01*
Y204070D01*
X1693050D01*
Y200870D01*
G01X1702470Y198120D02*
X1708670D01*
Y201320D01*
X1702470D01*
Y198120D01*
G01X1693070Y196730D02*
X1699270D01*
Y199930D01*
X1693070D01*
Y196730D01*
G01X1688960Y431712D02*
Y425512D01*
G01D02*
X1692160D01*
G01D02*
Y431712D01*
G01D02*
X1688960D01*
G01X1690777Y465350D02*
Y468550D01*
G01X1698322Y477183D02*
X1692122D01*
G01D02*
Y473983D01*
G01X1698322D02*
Y477183D01*
G01X1692122Y473983D02*
X1698322D01*
G01X1704120Y488762D02*
X1707320D01*
G01X1704120Y494962D02*
Y488762D01*
G01X1701320D02*
Y494962D01*
G01X1698120Y488762D02*
X1701320D01*
G01X1698120Y494962D02*
Y488762D01*
G01X1695939Y489678D02*
Y495878D01*
G01X1692739Y489678D02*
X1695939D01*
G01X1692739Y495878D02*
Y489678D01*
G01X1692086Y488406D02*
Y485206D01*
G01X1698286Y488406D02*
X1692086D01*
G01X1698286Y485206D02*
Y488406D01*
G01X1692086Y485206D02*
X1698286D01*
G01X1692860Y483022D02*
Y479822D01*
G01X1699060Y483022D02*
X1692860D01*
G01X1699060Y479822D02*
Y483022D01*
G01X1692860Y479822D02*
X1699060D01*
G01X1707320Y494962D02*
X1704120D01*
G01X1701320D02*
X1698120D01*
G01X1700750Y510152D02*
X1697550D01*
G01X1700750Y503952D02*
Y510152D01*
G01X1697550D02*
Y503952D01*
G01D02*
X1700750D01*
G01X1695939Y495878D02*
X1692739D01*
G01X1689769Y500679D02*
Y503879D01*
G01X1698376Y519907D02*
Y523107D01*
G01X1692176Y519907D02*
X1698376D01*
G01X1692176Y523107D02*
Y519907D01*
G01X1698376Y523107D02*
X1692176D01*
G01X1698376Y523907D02*
Y527107D01*
G01X1692176Y523907D02*
X1698376D01*
G01X1692176Y527107D02*
Y523907D01*
G01X1698376Y535907D02*
Y539107D01*
G01X1692176D02*
Y535907D01*
G01X1698376Y539107D02*
X1692176D01*
G01Y535907D02*
X1698376D01*
G01Y527107D02*
X1692176D01*
G01X1698376Y539907D02*
Y543107D01*
G01X1692176Y539907D02*
X1698376D01*
G01X1692176Y543107D02*
Y539907D01*
G01X1698376Y527907D02*
Y531107D01*
G01X1692176Y527907D02*
X1698376D01*
G01X1692176Y531107D02*
Y527907D01*
G01X1698376Y531107D02*
X1692176D01*
G01X1698376Y531907D02*
Y535107D01*
G01X1692176Y531907D02*
X1698376D01*
G01X1692176Y535107D02*
Y531907D01*
G01X1698376Y535107D02*
X1692176D01*
G01X1698376Y543107D02*
X1692176D01*
G01X1698376Y543907D02*
Y547107D01*
G01X1692176Y543907D02*
X1698376D01*
G01X1692176Y547107D02*
Y543907D01*
G01X1698376Y547107D02*
X1692176D01*
G01X1704296Y704847D02*
X1707496D01*
G01X1704296Y711047D02*
Y704847D01*
G01X1707617Y700565D02*
X1704417D01*
G01Y694365D02*
X1707617D01*
G01X1704417Y700565D02*
Y694365D01*
G01X1703667Y700565D02*
X1700467D01*
G01X1703667Y694365D02*
Y700565D01*
G01X1700467Y694365D02*
X1703667D01*
G01X1700467Y700565D02*
Y694365D01*
G01X1707496Y711047D02*
X1704296D01*
G01X1701248Y758968D02*
X1704448D01*
G01X1701248Y765168D02*
Y758968D01*
G01X1704448Y765168D02*
X1701248D01*
G01X1704448Y758968D02*
Y765168D01*
G01X1703429Y1224710D02*
X1706629D01*
G01X1703429Y1230910D02*
Y1224710D01*
G01X1706073Y1235879D02*
X1704105Y1233910D01*
G01Y1237848D02*
X1706073Y1235879D01*
G01X1704105Y1233910D02*
Y1237848D01*
G01X1697236Y1238635D02*
Y1233123D01*
G01X1713384Y1238635D02*
X1697236D01*
G01Y1233123D02*
X1713384D01*
G01X1706629Y1230910D02*
X1703429D01*
G01X1693641Y1255344D02*
Y1258544D01*
G01X1707403Y1251537D02*
X1704203D01*
G01Y1245337D02*
X1707403D01*
G01X1704203Y1251537D02*
Y1245337D01*
G01X1700614Y1252644D02*
Y1255844D01*
G01X1694414Y1252644D02*
X1700614D01*
G01X1694414Y1255844D02*
Y1252644D01*
G01X1700614Y1255844D02*
X1694414D01*
G01X1706613Y1258489D02*
X1703413D01*
G01Y1252289D02*
X1706613D01*
G01X1703413Y1258489D02*
Y1252289D01*
G01X1692118Y1252680D02*
X1688918D01*
G01X1692118Y1246480D02*
Y1252680D01*
G01X1688918Y1246480D02*
X1692118D01*
G01X1688918Y1252680D02*
Y1246480D01*
G01X1693541Y1259944D02*
Y1271944D01*
G01X1703541Y1259944D02*
X1709541D01*
G01X1703541Y1271944D02*
Y1259944D01*
G01X1709541Y1271944D02*
X1703541D01*
G01X1697954Y1383662D02*
Y1395662D01*
G01X1691954Y1383662D02*
X1697954D01*
G01X1691954Y1395662D02*
Y1383662D01*
G01X1691165Y1386865D02*
Y1393065D01*
G01X1697954Y1395662D02*
X1691954D01*
G01X1692392Y1419619D02*
Y1431619D01*
G01X1691827Y1440735D02*
X1703827D01*
G01X1691827Y1446735D02*
Y1440735D01*
G01X1703827Y1446735D02*
X1691827D01*
G01X1703827Y1440735D02*
Y1446735D01*
G01X1708425Y16792D02*
X1711625D01*
G01X1708425Y22992D02*
Y16792D01*
G01X1711625D02*
Y22992D01*
G01X1711663Y41254D02*
Y38054D01*
G01X1717863D02*
Y41254D01*
G01X1711663Y38054D02*
X1717863D01*
G01X1711625Y22992D02*
X1708425D01*
G01X1711573Y29644D02*
X1714773D01*
G01X1711573Y35844D02*
Y29644D01*
G01X1714773Y35844D02*
X1711573D01*
G01X1714773Y29644D02*
Y35844D01*
G01X1717863Y41254D02*
X1711663D01*
G01Y45254D02*
Y42054D01*
G01X1717863Y45254D02*
X1711663D01*
G01X1717863Y42054D02*
Y45254D01*
G01X1711663Y42054D02*
X1717863D01*
G01X1711663Y49254D02*
Y46054D01*
G01X1717863Y49254D02*
X1711663D01*
G01X1717863Y46054D02*
Y49254D01*
G01X1711663Y46054D02*
X1717863D01*
G01X1711663Y53254D02*
Y50054D01*
G01X1717863Y53254D02*
X1711663D01*
G01X1717863Y50054D02*
Y53254D01*
G01X1711663Y50054D02*
X1717863D01*
G01X1706400Y91762D02*
X1709600D01*
G01X1706400Y97962D02*
Y91762D01*
G01X1709600Y97962D02*
X1706400D01*
G01X1709600Y91762D02*
Y97962D01*
G01X1717647Y184460D02*
X1717699Y184153D01*
X1717905Y183885D01*
X1718215Y183655D01*
X1718577Y183502D01*
X1718990Y183425D01*
X1719404D01*
X1719817Y183502D01*
X1720179Y183655D01*
X1720489Y183885D01*
X1720695Y184153D01*
X1720747Y184460D01*
X1720695Y184767D01*
X1720489Y185035D01*
X1720179Y185265D01*
X1719817Y185418D01*
X1719404Y185495D01*
X1718990D01*
X1718577Y185418D01*
X1718215Y185265D01*
X1717905Y185035D01*
X1717699Y184767D01*
X1717647Y184460D01*
G01X1718474Y184767D02*
X1717647Y185227D01*
G01X1720230Y186832D02*
X1720540Y187062D01*
X1720695Y187330D01*
X1720747Y187637D01*
X1720644Y188020D01*
X1720385Y188288D01*
X1720075Y188365D01*
X1719765Y188327D01*
X1719507Y188173D01*
X1718990Y187407D01*
X1718629Y187062D01*
X1718112Y186832D01*
X1717647Y186755D01*
Y188365D01*
G01X1718267Y189817D02*
X1717905Y190047D01*
X1717699Y190353D01*
X1717647Y190698D01*
X1717699Y191005D01*
X1717957Y191312D01*
X1718267Y191503D01*
X1718577Y191542D01*
X1718939Y191465D01*
X1719197Y191197D01*
X1719300Y190928D01*
Y190583D01*
G01Y190928D02*
X1719455Y191158D01*
X1719714Y191350D01*
X1720024Y191427D01*
X1720334Y191350D01*
X1720592Y191158D01*
X1720747Y190813D01*
X1720695Y190468D01*
X1720489Y190123D01*
G01X1718939Y193032D02*
X1719300Y193300D01*
X1719507Y193530D01*
X1719610Y193837D01*
X1719507Y194105D01*
X1719300Y194297D01*
X1718990Y194450D01*
X1718629Y194488D01*
X1718319Y194450D01*
X1718009Y194297D01*
X1717750Y194067D01*
X1717647Y193798D01*
X1717750Y193492D01*
X1718060Y193223D01*
X1718525Y193070D01*
X1719042Y193032D01*
X1719714Y193108D01*
X1720075Y193223D01*
X1720437Y193415D01*
X1720695Y193683D01*
X1720747Y193952D01*
X1720644Y194220D01*
X1720385Y194412D01*
G01X1716411Y183663D02*
Y187010D01*
X1714211Y188910D01*
X1716411Y190810D01*
Y194157D01*
X1707749D01*
Y183663D01*
X1716411D01*
G01X1711220Y176880D02*
Y170680D01*
X1714420D01*
Y176880D01*
X1711220D01*
G01X1710280Y170650D02*
Y176850D01*
X1707080D01*
Y170650D01*
X1710280D01*
G01X1708760Y208800D02*
X1705560D01*
G01X1708760Y202600D02*
Y208800D01*
G01X1705560Y202600D02*
X1708760D01*
G01X1705560Y208800D02*
Y202600D01*
G01X1723461Y477352D02*
X1717261D01*
G01Y474152D02*
X1723461D01*
G01X1717261Y477352D02*
Y474152D01*
G01Y470652D02*
X1723461D01*
G01X1717261Y473852D02*
Y470652D01*
G01X1723461Y473852D02*
X1717261D01*
G01Y477652D02*
X1723461D01*
G01X1717261Y480852D02*
Y477652D01*
G01X1707320Y488762D02*
Y494962D01*
G01X1713320Y488762D02*
Y494962D01*
G01X1710120Y488762D02*
X1713320D01*
G01X1710120Y494962D02*
Y488762D01*
G01X1723461Y480852D02*
X1717261D01*
G01X1713320Y494962D02*
X1710120D01*
G01X1762606Y605455D02*
G03I-22900J0D01*
G01X1707496Y704847D02*
Y711047D01*
G01X1707617Y694365D02*
Y700565D01*
G01X1708457Y694365D02*
X1711657D01*
G01X1708457Y700565D02*
Y694365D01*
G01X1711657Y700565D02*
X1708457D01*
G01X1711657Y694365D02*
Y700565D01*
G01X1715206Y715537D02*
X1712006D01*
G01X1715206Y709337D02*
Y715537D01*
G01X1712006Y709337D02*
X1715206D01*
G01X1712006Y715537D02*
Y709337D01*
G01X1707886Y709387D02*
X1711086D01*
G01X1707886Y715587D02*
Y709387D01*
G01X1711086Y715587D02*
X1707886D01*
G01X1711086Y709387D02*
Y715587D01*
G01X1713355Y758976D02*
X1716555D01*
G01X1713355Y765176D02*
Y758976D01*
G01X1716555Y765176D02*
X1713355D01*
G01X1716555Y758976D02*
Y765176D01*
G01X1709315Y758976D02*
X1712515D01*
G01X1709315Y765176D02*
Y758976D01*
G01X1712515Y765176D02*
X1709315D01*
G01X1712515Y758976D02*
Y765176D01*
G01X1705348Y758968D02*
X1708548D01*
G01X1705348Y765168D02*
Y758968D01*
G01X1708548Y765168D02*
X1705348D01*
G01X1708548Y758968D02*
Y765168D01*
G01X1706629Y1224710D02*
Y1230910D01*
G01X1720499Y1235429D02*
X1718073D01*
G01X1706467Y1233910D02*
Y1237848D01*
G01X1714536Y1238629D02*
X1714036D01*
G01X1714536Y1233129D02*
Y1238629D01*
G01X1713786Y1233129D02*
X1714536D01*
G01X1713786Y1238379D02*
Y1233129D01*
G01X1713386Y1238379D02*
X1713786D01*
G01X1713386Y1238629D02*
Y1238379D01*
G01X1714086Y1238629D02*
X1713386D01*
G01X1714086Y1233129D02*
Y1238629D01*
G01X1713436Y1233129D02*
X1714086D01*
G01X1713436Y1233229D02*
Y1233129D01*
G01X1713384Y1233123D02*
Y1238635D01*
G01X1717141Y1258544D02*
Y1255344D01*
G01X1723341Y1258544D02*
X1717141D01*
G01Y1255344D02*
X1723341D01*
G01X1710613Y1258489D02*
X1707413D01*
G01X1710613Y1252289D02*
Y1258489D01*
G01X1707413Y1252289D02*
X1710613D01*
G01X1707413Y1258489D02*
Y1252289D01*
G01X1707403Y1245337D02*
Y1251537D01*
G01X1706613Y1252289D02*
Y1258489D01*
G01X1721783Y1254474D02*
X1718583D01*
G01Y1248274D02*
X1721783D01*
G01X1718583Y1254474D02*
Y1248274D01*
G01X1709541Y1259944D02*
Y1271944D01*
G01X1717241Y1259944D02*
X1723241D01*
G01X1717241Y1271944D02*
Y1259944D01*
G01X1723241Y1271944D02*
X1717241D01*
G01X1726826Y68930D02*
X1738826D01*
G01X1726826Y74930D02*
Y68930D01*
G01X1736894Y60039D02*
Y63239D01*
G01X1730694Y60039D02*
X1736894D01*
G01X1730694Y63239D02*
Y60039D01*
G01X1736894Y63239D02*
X1730694D01*
G01X1736942Y64149D02*
Y67349D01*
G01X1730742Y64149D02*
X1736942D01*
G01X1730742Y67349D02*
Y64149D01*
G01X1736942Y67349D02*
X1730742D01*
G01X1738826Y74930D02*
X1726826D01*
G01X1738630Y83364D02*
X1726630D01*
G01Y77364D02*
X1738630D01*
G01X1726630Y83364D02*
Y77364D01*
G01X1723461Y474152D02*
Y477352D01*
G01Y470652D02*
Y473852D01*
G01Y477652D02*
Y480852D01*
G01X1723341Y1255344D02*
Y1258544D01*
G01X1736314Y1252544D02*
Y1258744D01*
G01X1733114Y1252544D02*
X1736314D01*
G01X1733114Y1258744D02*
Y1252544D01*
G01X1730214Y1252744D02*
Y1255944D01*
G01X1724014Y1252744D02*
X1730214D01*
G01X1724014Y1255944D02*
Y1252744D01*
G01X1730214Y1255944D02*
X1724014D01*
G01X1721783Y1248274D02*
Y1254474D01*
G01X1723241Y1259944D02*
Y1271944D01*
G01X1733241Y1259944D02*
X1739241D01*
G01X1733241Y1271944D02*
Y1259944D01*
G01X1739241Y1271944D02*
X1733241D01*
G01X1736314Y1258744D02*
X1733114D01*
G01X1738826Y68930D02*
Y74930D01*
G01X1738630Y77364D02*
Y83364D01*
G01X1752771Y705121D02*
X1764771D01*
G01X1752771Y711121D02*
Y705121D01*
G01X1752977Y696940D02*
X1764977D01*
G01X1752977Y702940D02*
Y696940D01*
G01X1764977Y702940D02*
X1752977D01*
G01X1764771Y711121D02*
X1752771D01*
G01X1746841Y1258544D02*
Y1255344D01*
G01X1753041Y1258544D02*
X1746841D01*
G01X1753041Y1255344D02*
Y1258544D01*
G01X1746841Y1255344D02*
X1753041D01*
G01X1751290Y1249986D02*
X1748090D01*
G01X1751290Y1243786D02*
Y1249986D01*
G01X1748090Y1243786D02*
X1751290D01*
G01X1748090Y1249986D02*
Y1243786D01*
G01X1752941Y1259944D02*
Y1271944D01*
G01X1746941Y1259944D02*
X1752941D01*
G01X1746941Y1271944D02*
Y1259944D01*
G01X1752941Y1271944D02*
X1746941D01*
G01X1739241Y1259944D02*
Y1271944D01*
G01X1768300Y38609D02*
X1771500D01*
G01X1768300Y44809D02*
Y38609D01*
G01X1756475D02*
X1759675D01*
G01X1756475Y44809D02*
Y38609D01*
G01X1759675D02*
Y44809D01*
G01X1763675Y38609D02*
Y44809D01*
G01X1760475Y38609D02*
X1763675D01*
G01X1760475Y44809D02*
Y38609D01*
G01X1768191Y29754D02*
X1771391D01*
G01X1768191Y35954D02*
Y29754D01*
G01X1771391Y35954D02*
X1768191D01*
G01X1771500Y44809D02*
X1768300D01*
G01X1759675D02*
X1756475D01*
G01X1763675D02*
X1760475D01*
G01X1767898Y223628D02*
X1773898D01*
G01X1767898Y235628D02*
Y223628D01*
G01X1765878D02*
Y235628D01*
G01X1759878Y223628D02*
X1765878D01*
G01X1759878Y235628D02*
Y223628D01*
G01X1753778Y226428D02*
X1756978D01*
G01X1753778Y232628D02*
Y226428D01*
G01X1756978Y232628D02*
X1753778D01*
G01X1756978Y226428D02*
Y232628D01*
G01X1773898Y235628D02*
X1767898D01*
G01X1765878D02*
X1759878D01*
G01X1768966Y305059D02*
Y298859D01*
X1772166D01*
Y305059D01*
X1768966D01*
G01X1763080Y310642D02*
Y304442D01*
G01D02*
X1766280D01*
G01D02*
Y310642D01*
G01D02*
X1763080D01*
G01X1764771Y705121D02*
Y711121D01*
G01X1764977Y696940D02*
Y702940D01*
G01X1756512Y714848D02*
X1762712D01*
Y718048D01*
X1756512D01*
Y714848D01*
G01X1756612Y723048D02*
X1762812D01*
Y726248D01*
X1756612D01*
Y723048D01*
G01X1766114Y1258644D02*
X1762914D01*
G01X1766114Y1252444D02*
Y1258644D01*
G01X1762914Y1252444D02*
X1766114D01*
G01X1762914Y1258644D02*
Y1252444D01*
G01X1759714Y1252744D02*
Y1255944D01*
G01X1753514Y1252744D02*
X1759714D01*
G01X1753514Y1255944D02*
Y1252744D01*
G01X1759714Y1255944D02*
X1753514D01*
G01X1768941Y1259944D02*
Y1271944D01*
G01X1762941Y1259944D02*
X1768941D01*
G01X1762941Y1271944D02*
Y1259944D01*
G01X1768941Y1271944D02*
X1762941D01*
G01X1777279Y1714960D02*
G02I-10350J0D01*
G01X1777975Y12122D02*
X1781175D01*
G01X1777975Y18322D02*
Y12122D01*
G01X1781175Y18322D02*
X1777975D01*
G01X1781175Y12122D02*
Y18322D01*
G01X1772835Y12142D02*
X1776035D01*
G01X1772835Y18342D02*
Y12142D01*
G01X1776035Y18342D02*
X1772835D01*
G01X1776035Y12142D02*
Y18342D01*
G01X1771500Y38609D02*
Y44809D01*
G01X1775154Y38609D02*
Y44809D01*
G01X1771954Y38609D02*
X1775154D01*
G01X1771954Y44809D02*
Y38609D01*
G01X1775391Y35954D02*
X1772191D01*
G01X1775391Y29754D02*
Y35954D01*
G01X1772191Y29754D02*
X1775391D01*
G01X1772191Y35954D02*
Y29754D01*
G01X1771391D02*
Y35954D01*
G01X1779354Y44969D02*
X1776154D01*
G01X1779354Y38769D02*
Y44969D01*
G01X1776154Y38769D02*
X1779354D01*
G01X1776154Y44969D02*
Y38769D01*
G01X1783590Y44855D02*
X1780390D01*
G01X1783590Y38655D02*
Y44855D01*
G01X1780390Y38655D02*
X1783590D01*
G01X1780390Y44855D02*
Y38655D01*
G01X1775154Y44809D02*
X1771954D01*
G01X1776475Y172303D02*
Y175503D01*
G01X1770275Y172303D02*
X1776475D01*
G01X1770275Y175503D02*
Y172303D01*
G01X1776475Y175503D02*
X1770275D01*
G01X1776475Y176703D02*
Y179903D01*
G01X1770275Y176703D02*
X1776475D01*
G01X1770275Y179903D02*
Y176703D01*
G01X1776475Y179903D02*
X1770275D01*
G01X1773898Y223628D02*
Y235628D01*
G01X1782378Y223628D02*
Y235628D01*
G01X1776378Y223628D02*
X1782378D01*
G01X1776378Y235628D02*
Y223628D01*
G01X1782378Y235628D02*
X1776378D01*
G01X1781810Y274492D02*
X1787810D01*
Y286492D01*
X1781810D01*
Y274492D01*
G01X1783222Y307219D02*
X1785462D01*
G01X1784249Y305594D02*
Y308844D01*
G01X1785328Y314584D02*
X1788428D01*
Y315350D01*
X1788273Y315657D01*
X1788066Y315887D01*
X1787756Y316079D01*
X1787395Y316232D01*
X1786878Y316270D01*
X1786361Y316232D01*
X1786000Y316079D01*
X1785690Y315887D01*
X1785483Y315657D01*
X1785328Y315350D01*
Y314584D01*
G01Y318527D02*
X1788428D01*
X1787808Y318067D01*
G01X1785328D02*
Y318987D01*
G01Y322087D02*
X1788428D01*
X1786206Y320669D01*
Y322585D01*
G01X1785793Y323884D02*
X1785535Y324114D01*
X1785380Y324382D01*
X1785328Y324727D01*
X1785431Y325072D01*
X1785638Y325340D01*
X1786000Y325532D01*
X1786413Y325570D01*
X1786826Y325494D01*
X1787085Y325302D01*
X1787291Y325034D01*
X1787343Y324765D01*
X1787291Y324497D01*
X1787085Y324152D01*
X1788428Y324267D01*
Y325302D01*
G01X1783256Y310949D02*
Y327097D01*
X1777744D01*
Y310949D01*
X1783256D01*
G01X1776137Y305144D02*
X1772937D01*
G01X1776137Y298944D02*
Y305144D01*
G01X1772937Y298944D02*
X1776137D01*
G01X1772937Y305144D02*
Y298944D01*
G01X1780919Y308280D02*
X1777719D01*
G01X1780919Y302080D02*
Y308280D01*
G01X1777719Y302080D02*
X1780919D01*
G01X1777719Y308280D02*
Y302080D01*
G01X1783944Y333016D02*
Y330590D01*
G01X1782469Y317818D02*
X1778531D01*
X1780500Y319786D01*
X1782469Y317818D01*
G01Y320180D02*
X1778531D01*
G01X1783150Y327149D02*
X1783250D01*
Y327799D01*
X1777750D01*
Y327099D01*
X1778000D01*
Y327499D01*
X1783250D01*
Y328249D01*
X1777750D01*
Y327749D01*
G01X1776541Y1258544D02*
Y1255344D01*
G01X1782741Y1258544D02*
X1776541D01*
G01X1782741Y1255344D02*
Y1258544D01*
G01X1776541Y1255344D02*
X1782741D01*
G01X1783714Y1253144D02*
X1789914D01*
G01X1783714Y1256344D02*
Y1253144D01*
G01X1789914Y1256344D02*
X1783714D01*
G01X1780389Y1251745D02*
X1777189D01*
G01X1780389Y1245545D02*
Y1251745D01*
G01X1777189Y1245545D02*
X1780389D01*
G01X1777189Y1251745D02*
Y1245545D01*
G01X1782641Y1259944D02*
Y1271944D01*
G01X1776641Y1259944D02*
X1782641D01*
G01X1776641Y1271944D02*
Y1259944D01*
G01X1782641Y1271944D02*
X1776641D01*
G01X1830942Y1581739D02*
G03X1830586Y1556144I-22750J-12484D01*
G01X1776760Y1622713D02*
Y1625813D01*
X1777220Y1625193D01*
G01Y1622713D02*
X1776300D01*
G01X1778503Y1644563D02*
X1778273Y1644201D01*
X1777967Y1643995D01*
X1777622Y1643943D01*
X1777315Y1643995D01*
X1777008Y1644253D01*
X1776817Y1644563D01*
X1776778Y1644873D01*
X1776855Y1645235D01*
X1777123Y1645493D01*
X1777392Y1645596D01*
X1777737D01*
G01X1777392D02*
X1777162Y1645751D01*
X1776970Y1646010D01*
X1776893Y1646320D01*
X1776970Y1646630D01*
X1777162Y1646888D01*
X1777507Y1647043D01*
X1777852Y1646991D01*
X1778197Y1646785D01*
G01X1789306Y48440D02*
Y54640D01*
G01X1786106Y48440D02*
X1789306D01*
G01X1786106Y54640D02*
Y48440D01*
G01X1789306Y54640D02*
X1786106D01*
G01X1793306Y48440D02*
Y54640D01*
G01X1790106Y48440D02*
X1793306D01*
G01X1790106Y54640D02*
Y48440D01*
G01X1793306Y54640D02*
X1790106D01*
G01X1788850Y274502D02*
X1794850D01*
Y286502D01*
X1788850D01*
Y274502D01*
G01X1793320Y307532D02*
X1787320D01*
Y295532D01*
X1793320D01*
Y307532D01*
G01X1835871Y514696D02*
G03X1835297Y489231I-22892J-12223D01*
G01X1804243Y1227232D02*
Y1230332D01*
X1803477D01*
X1803170Y1230177D01*
X1802940Y1229970D01*
X1802748Y1229660D01*
X1802595Y1229299D01*
X1802557Y1228782D01*
X1802595Y1228265D01*
X1802748Y1227904D01*
X1802940Y1227594D01*
X1803170Y1227387D01*
X1803477Y1227232D01*
X1804243D01*
G01X1799840D02*
Y1230332D01*
X1801258Y1228110D01*
X1799342D01*
G01X1798043Y1227697D02*
X1797813Y1227439D01*
X1797545Y1227284D01*
X1797200Y1227232D01*
X1796855Y1227335D01*
X1796587Y1227542D01*
X1796395Y1227904D01*
X1796357Y1228317D01*
X1796433Y1228730D01*
X1796625Y1228989D01*
X1796893Y1229195D01*
X1797162Y1229247D01*
X1797430Y1229195D01*
X1797775Y1228989D01*
X1797660Y1230332D01*
X1796625D01*
G01X1799017Y1236290D02*
Y1242490D01*
G01X1795817Y1236290D02*
X1799017D01*
G01X1795817Y1242490D02*
Y1236290D01*
G01X1801720Y1254826D02*
X1807920D01*
G01X1801720Y1258026D02*
Y1254826D01*
G01X1807920Y1258026D02*
X1801720D01*
G01X1799017Y1242490D02*
X1795817D01*
G01X1792189Y1254619D02*
Y1251419D01*
G01X1798389Y1254619D02*
X1792189D01*
G01X1798389Y1251419D02*
Y1254619D01*
G01X1792189Y1251419D02*
X1798389D01*
G01X1799017Y1249490D02*
X1795817D01*
G01X1799017Y1243290D02*
Y1249490D01*
G01X1795817Y1243290D02*
X1799017D01*
G01X1795817Y1249490D02*
Y1243290D01*
G01X1789914Y1253144D02*
Y1256344D01*
G01X1792189Y1258419D02*
Y1255219D01*
G01X1798389Y1258419D02*
X1792189D01*
G01X1798389Y1255219D02*
Y1258419D01*
G01X1792189Y1255219D02*
X1798389D01*
G01X1798641Y1259944D02*
Y1271944D01*
G01X1792641Y1259944D02*
X1798641D01*
G01X1792641Y1271944D02*
Y1259944D01*
G01X1798641Y1271944D02*
X1792641D01*
G01X1838992Y1431862D02*
G03X1838058Y1407326I-19781J-11533D01*
G01X1797070Y1507252D02*
X1790870D01*
G01D02*
Y1504052D01*
G01D02*
X1797070D01*
G01D02*
Y1507252D01*
G01X1808122Y1229761D02*
X1810362D01*
G01X1809149Y1228136D02*
Y1231386D01*
G01X1809349Y1241948D02*
X1811318Y1239980D01*
G01X1807380D02*
X1809349Y1241948D01*
G01X1811318Y1239980D02*
X1807380D01*
G01X1811318Y1242342D02*
X1807380D01*
G01X1806593Y1233111D02*
X1812105D01*
G01X1806593Y1249259D02*
Y1233111D01*
G01X1812105D02*
Y1249259D01*
G01X1817960Y1242361D02*
X1814760D01*
G01X1817960Y1236161D02*
Y1242361D01*
G01X1814760Y1236161D02*
X1817960D01*
G01X1814760Y1242361D02*
Y1236161D01*
G01X1823230Y1247485D02*
Y1245059D01*
G01X1806599Y1250411D02*
Y1249911D01*
G01X1812099Y1250411D02*
X1806599D01*
G01X1812099Y1249661D02*
Y1250411D01*
G01X1806849Y1249661D02*
X1812099D01*
G01X1806849Y1249261D02*
Y1249661D01*
G01X1806599Y1249261D02*
X1806849D01*
G01X1806599Y1249961D02*
Y1249261D01*
G01X1812099Y1249961D02*
X1806599D01*
G01X1812099Y1249311D02*
Y1249961D01*
G01X1811999Y1249311D02*
X1812099D01*
G01X1812105Y1249259D02*
X1806593D01*
G01X1807920Y1254826D02*
Y1258026D01*
G01X1818212Y1258185D02*
X1815012D01*
G01X1818212Y1251985D02*
Y1258185D01*
G01X1815012Y1251985D02*
X1818212D01*
G01X1815012Y1258185D02*
Y1251985D01*
G01X1812554Y1257464D02*
X1809354D01*
G01X1812554Y1251264D02*
Y1257464D01*
G01X1809354Y1251264D02*
X1812554D01*
G01X1809354Y1257464D02*
Y1251264D01*
G01X1812341Y1259944D02*
Y1271944D01*
G01X1806341Y1259944D02*
X1812341D01*
G01X1806341Y1271944D02*
Y1259944D01*
G01X1812341Y1271944D02*
X1806341D01*
G01X1813714Y1259944D02*
X1819714D01*
G01X1813714Y1271944D02*
Y1259944D01*
G01X1819714Y1271944D02*
X1813714D01*
G01X1808222Y1512037D02*
Y1508837D01*
G01X1814422Y1512037D02*
X1808222D01*
G01X1814422Y1508837D02*
Y1512037D01*
G01X1808222Y1508837D02*
X1814422D01*
G01X1819714Y1259944D02*
Y1271944D01*
G01X1869000Y346345D02*
X1872100Y347955D01*
G01Y346345D02*
X1869000Y347955D01*
G01Y350710D02*
X1872100D01*
X1869878Y349292D01*
Y351208D01*
G01X1869000Y353273D02*
X1869672Y353350D01*
X1870240Y353465D01*
X1870757Y353618D01*
X1871325Y353810D01*
X1872100Y354117D01*
Y352583D01*
G01X1884705Y344948D02*
X1883605D01*
G01X1874705D02*
X1874155D01*
Y354948D01*
G01X1881655D02*
X1886655D01*
G01X1874155D02*
X1876655D01*
G01Y458898D02*
X1874155D01*
Y468898D01*
X1874705D01*
G01X1886655Y458898D02*
X1881655D01*
G01X1883605Y468898D02*
X1884705D01*
G01X1869000Y593845D02*
X1872100Y595455D01*
G01Y593845D02*
X1869000Y595455D01*
G01X1869620Y596907D02*
X1869258Y597137D01*
X1869052Y597443D01*
X1869000Y597788D01*
X1869052Y598095D01*
X1869310Y598402D01*
X1869620Y598593D01*
X1869930Y598632D01*
X1870292Y598555D01*
X1870550Y598287D01*
X1870653Y598018D01*
Y597673D01*
G01Y598018D02*
X1870808Y598248D01*
X1871067Y598440D01*
X1871377Y598517D01*
X1871687Y598440D01*
X1871945Y598248D01*
X1872100Y597903D01*
X1872048Y597558D01*
X1871842Y597213D01*
G01X1869000Y600850D02*
X1869052Y601118D01*
X1869207Y601425D01*
X1869465Y601617D01*
X1869827Y601693D01*
X1870188Y601617D01*
X1870498Y601387D01*
X1870653Y601042D01*
Y600658D01*
X1870757Y600428D01*
X1871015Y600237D01*
X1871377Y600160D01*
X1871738Y600275D01*
X1871997Y600543D01*
X1872100Y600850D01*
X1871997Y601157D01*
X1871738Y601425D01*
X1871377Y601540D01*
X1871015Y601463D01*
X1870757Y601272D01*
X1870653Y601042D01*
Y600658D01*
X1870498Y600313D01*
X1870188Y600083D01*
X1869827Y600007D01*
X1869465Y600083D01*
X1869207Y600275D01*
X1869052Y600582D01*
X1869000Y600850D01*
G01X1884705Y592848D02*
X1883605D01*
G01X1874705D02*
X1874155D01*
Y602848D01*
G01X1881655D02*
X1886655D01*
G01X1874155D02*
X1876655D01*
G01X1868500Y708345D02*
X1871600Y709955D01*
G01Y708345D02*
X1868500Y709955D01*
G01Y712710D02*
X1871600D01*
X1869378Y711292D01*
Y713208D01*
G01X1869792Y714622D02*
X1870153Y714890D01*
X1870360Y715120D01*
X1870463Y715427D01*
X1870360Y715695D01*
X1870153Y715887D01*
X1869843Y716040D01*
X1869482Y716078D01*
X1869172Y716040D01*
X1868862Y715887D01*
X1868603Y715657D01*
X1868500Y715388D01*
X1868603Y715082D01*
X1868913Y714813D01*
X1869378Y714660D01*
X1869895Y714622D01*
X1870567Y714698D01*
X1870928Y714813D01*
X1871290Y715005D01*
X1871548Y715273D01*
X1871600Y715542D01*
X1871497Y715810D01*
X1871238Y716002D01*
G01X1876655Y706798D02*
X1874155D01*
Y716798D01*
X1874705D01*
G01X1883605D02*
X1884705D01*
G01X1886655Y706798D02*
X1881655D01*
G01X1868607Y1007063D02*
X1881720Y972487D01*
G01D02*
X1894833Y1007063D01*
G01D02*
X1868607D01*
G01X1868949Y1284169D02*
X1872049D01*
Y1284935D01*
X1871894Y1285242D01*
X1871687Y1285472D01*
X1871377Y1285664D01*
X1871016Y1285817D01*
X1870499Y1285855D01*
X1869982Y1285817D01*
X1869621Y1285664D01*
X1869311Y1285472D01*
X1869104Y1285242D01*
X1868949Y1284935D01*
Y1284169D01*
G01X1870602Y1288419D02*
X1870757Y1288572D01*
X1871016Y1288687D01*
X1871377Y1288764D01*
X1871687Y1288687D01*
X1871894Y1288534D01*
X1872049Y1288265D01*
Y1287230D01*
X1868949D01*
Y1288495D01*
X1869156Y1288764D01*
X1869466Y1288917D01*
X1869827Y1288994D01*
X1870189Y1288917D01*
X1870499Y1288687D01*
X1870602Y1288419D01*
Y1287230D01*
G01X1868949Y1291212D02*
X1872049D01*
X1871429Y1290752D01*
G01X1868949D02*
Y1291672D01*
G01X1870241Y1293584D02*
X1870602Y1293852D01*
X1870809Y1294082D01*
X1870912Y1294389D01*
X1870809Y1294657D01*
X1870602Y1294849D01*
X1870292Y1295002D01*
X1869931Y1295040D01*
X1869621Y1295002D01*
X1869311Y1294849D01*
X1869052Y1294619D01*
X1868949Y1294350D01*
X1869052Y1294044D01*
X1869362Y1293775D01*
X1869827Y1293622D01*
X1870344Y1293584D01*
X1871016Y1293660D01*
X1871377Y1293775D01*
X1871739Y1293967D01*
X1871997Y1294235D01*
X1872049Y1294504D01*
X1871946Y1294772D01*
X1871687Y1294964D01*
G01X1880836Y1332956D02*
X1867723Y1298380D01*
G01D02*
X1893949D01*
G01X1868098Y1369767D02*
X1881211Y1335191D01*
G01D02*
X1894324Y1369767D01*
G01X1893949Y1298380D02*
X1880836Y1332956D01*
G01X1894324Y1369767D02*
X1868098D01*
G01X1869819Y1649849D02*
X1872919D01*
Y1650615D01*
X1872764Y1650922D01*
X1872557Y1651152D01*
X1872247Y1651344D01*
X1871886Y1651497D01*
X1871369Y1651535D01*
X1870852Y1651497D01*
X1870491Y1651344D01*
X1870181Y1651152D01*
X1869974Y1650922D01*
X1869819Y1650615D01*
Y1649849D01*
G01X1871472Y1654099D02*
X1871627Y1654252D01*
X1871886Y1654367D01*
X1872247Y1654444D01*
X1872557Y1654367D01*
X1872764Y1654214D01*
X1872919Y1653945D01*
Y1652910D01*
X1869819D01*
Y1654175D01*
X1870026Y1654444D01*
X1870336Y1654597D01*
X1870697Y1654674D01*
X1871059Y1654597D01*
X1871369Y1654367D01*
X1871472Y1654099D01*
Y1652910D01*
G01X1869819Y1656892D02*
X1872919D01*
X1872299Y1656432D01*
G01X1869819D02*
Y1657352D01*
G01X1870284Y1659149D02*
X1870026Y1659379D01*
X1869871Y1659647D01*
X1869819Y1659992D01*
X1869922Y1660337D01*
X1870129Y1660605D01*
X1870491Y1660797D01*
X1870904Y1660835D01*
X1871317Y1660759D01*
X1871576Y1660567D01*
X1871782Y1660299D01*
X1871834Y1660030D01*
X1871782Y1659762D01*
X1871576Y1659417D01*
X1872919Y1659532D01*
Y1660567D01*
G01X1881165Y1697999D02*
X1868052Y1663423D01*
G01D02*
X1894278D01*
G01D02*
X1881165Y1697999D01*
G01X1895275Y-19342D02*
Y-9342D01*
G01X1895825Y-19342D02*
X1895275D01*
G01Y-9342D02*
X1897775D01*
G01X1891655Y354948D02*
X1894155D01*
Y344948D01*
X1893605D01*
G01X1896500Y460345D02*
X1899600Y461955D01*
G01Y460345D02*
X1896500Y461955D01*
G01X1897120Y463407D02*
X1896758Y463637D01*
X1896552Y463943D01*
X1896500Y464288D01*
X1896552Y464595D01*
X1896810Y464902D01*
X1897120Y465093D01*
X1897430Y465132D01*
X1897792Y465055D01*
X1898050Y464787D01*
X1898153Y464518D01*
Y464173D01*
G01Y464518D02*
X1898308Y464748D01*
X1898567Y464940D01*
X1898877Y465017D01*
X1899187Y464940D01*
X1899445Y464748D01*
X1899600Y464403D01*
X1899548Y464058D01*
X1899342Y463713D01*
G01X1896862Y466698D02*
X1896603Y466967D01*
X1896500Y467273D01*
X1896603Y467580D01*
X1896913Y467848D01*
X1897378Y468040D01*
X1897843Y468117D01*
X1898412D01*
X1898877Y468040D01*
X1899290Y467848D01*
X1899497Y467618D01*
X1899600Y467350D01*
X1899497Y467043D01*
X1899290Y466813D01*
X1898980Y466660D01*
X1898567Y466583D01*
X1898205Y466660D01*
X1897843Y466852D01*
X1897637Y467082D01*
X1897585Y467350D01*
X1897688Y467657D01*
X1897947Y467887D01*
X1898412Y468117D01*
G01X1893605Y468898D02*
X1894155D01*
Y458898D01*
G01D02*
X1891655D01*
G01X1896716Y568391D02*
X1899816Y570001D01*
G01Y568391D02*
X1896716Y570001D01*
G01Y572296D02*
X1899816D01*
X1899196Y571836D01*
G01X1896716D02*
Y572756D01*
G01Y575396D02*
X1896768Y575664D01*
X1896923Y575971D01*
X1897181Y576163D01*
X1897543Y576239D01*
X1897904Y576163D01*
X1898214Y575933D01*
X1898369Y575588D01*
Y575204D01*
X1898473Y574974D01*
X1898731Y574783D01*
X1899093Y574706D01*
X1899454Y574821D01*
X1899713Y575089D01*
X1899816Y575396D01*
X1899713Y575703D01*
X1899454Y575971D01*
X1899093Y576086D01*
X1898731Y576009D01*
X1898473Y575818D01*
X1898369Y575588D01*
Y575204D01*
X1898214Y574859D01*
X1897904Y574629D01*
X1897543Y574553D01*
X1897181Y574629D01*
X1896923Y574821D01*
X1896768Y575128D01*
X1896716Y575396D01*
G01X1895275Y582858D02*
Y592858D01*
G01X1897775Y582858D02*
X1895275D01*
G01Y592858D02*
X1895825D01*
G01X1891655Y602848D02*
X1894155D01*
Y592848D01*
X1893605D01*
G01X1895825Y716808D02*
X1895275D01*
Y726808D01*
G01X1893605Y716798D02*
X1894155D01*
Y706798D01*
G01D02*
X1891655D01*
G01X1895275Y726808D02*
X1897775D01*
G01Y830758D02*
X1895275D01*
Y840758D01*
X1895825D01*
G01X1890039Y1011859D02*
X1893139D01*
Y1012625D01*
X1892984Y1012932D01*
X1892777Y1013162D01*
X1892467Y1013354D01*
X1892106Y1013507D01*
X1891589Y1013545D01*
X1891072Y1013507D01*
X1890711Y1013354D01*
X1890401Y1013162D01*
X1890194Y1012932D01*
X1890039Y1012625D01*
Y1011859D01*
G01X1891692Y1016109D02*
X1891847Y1016262D01*
X1892106Y1016377D01*
X1892467Y1016454D01*
X1892777Y1016377D01*
X1892984Y1016224D01*
X1893139Y1015955D01*
Y1014920D01*
X1890039D01*
Y1016185D01*
X1890246Y1016454D01*
X1890556Y1016607D01*
X1890917Y1016684D01*
X1891279Y1016607D01*
X1891589Y1016377D01*
X1891692Y1016109D01*
Y1014920D01*
G01X1890039Y1018902D02*
X1893139D01*
X1892519Y1018442D01*
G01X1890039D02*
Y1019362D01*
G01X1892622Y1021274D02*
X1892932Y1021504D01*
X1893087Y1021772D01*
X1893139Y1022079D01*
X1893036Y1022462D01*
X1892777Y1022730D01*
X1892467Y1022807D01*
X1892157Y1022769D01*
X1891899Y1022615D01*
X1891382Y1021849D01*
X1891021Y1021504D01*
X1890504Y1021274D01*
X1890039Y1021197D01*
Y1022807D01*
G01X1889669Y1372449D02*
X1892769D01*
Y1373215D01*
X1892614Y1373522D01*
X1892407Y1373752D01*
X1892097Y1373944D01*
X1891736Y1374097D01*
X1891219Y1374135D01*
X1890702Y1374097D01*
X1890341Y1373944D01*
X1890031Y1373752D01*
X1889824Y1373522D01*
X1889669Y1373215D01*
Y1372449D01*
G01X1891322Y1376699D02*
X1891477Y1376852D01*
X1891736Y1376967D01*
X1892097Y1377044D01*
X1892407Y1376967D01*
X1892614Y1376814D01*
X1892769Y1376545D01*
Y1375510D01*
X1889669D01*
Y1376775D01*
X1889876Y1377044D01*
X1890186Y1377197D01*
X1890547Y1377274D01*
X1890909Y1377197D01*
X1891219Y1376967D01*
X1891322Y1376699D01*
Y1375510D01*
G01X1889669Y1379492D02*
X1892769D01*
X1892149Y1379032D01*
G01X1889669D02*
Y1379952D01*
G01Y1382592D02*
X1892769D01*
X1892149Y1382132D01*
G01X1889669D02*
Y1383052D01*
G01X1915275Y-9342D02*
Y-19342D01*
G01X1905825D02*
X1904725D01*
G01X1915275D02*
X1914725D01*
G01X1911890Y-3665D02*
X1914990Y-2055D01*
G01Y-3665D02*
X1911890Y-2055D01*
G01X1914473Y-488D02*
X1914783Y-258D01*
X1914938Y10D01*
X1914990Y317D01*
X1914887Y700D01*
X1914628Y968D01*
X1914318Y1045D01*
X1914008Y1007D01*
X1913750Y853D01*
X1913233Y87D01*
X1912872Y-258D01*
X1912355Y-488D01*
X1911890Y-565D01*
Y1045D01*
G01Y3800D02*
X1914990D01*
X1912768Y2382D01*
Y4298D01*
G01X1902775Y-9342D02*
X1907775D01*
G01X1912775D02*
X1915275D01*
G01Y592858D02*
Y582858D01*
G01X1907775D02*
X1902775D01*
G01X1915275D02*
X1912775D01*
G01X1904725Y592858D02*
X1905825D01*
G01X1914725D02*
X1915275D01*
G01X1912775Y726808D02*
X1915275D01*
Y716808D01*
X1914725D01*
G01X1905825D02*
X1904725D01*
G01X1902775Y726808D02*
X1907775D01*
G01X1914725Y840758D02*
X1915275D01*
Y830758D01*
G01X1907775D02*
X1902775D01*
G01X1915275D02*
X1912775D01*
G01X1904725Y840758D02*
X1905825D01*
G01X1915406Y1182331D02*
X1918506Y1183941D01*
G01Y1182331D02*
X1915406Y1183941D01*
G01Y1186236D02*
X1918506D01*
X1917886Y1185776D01*
G01X1915406D02*
Y1186696D01*
G01X1917989Y1188608D02*
X1918299Y1188838D01*
X1918454Y1189106D01*
X1918506Y1189413D01*
X1918403Y1189796D01*
X1918144Y1190064D01*
X1917834Y1190141D01*
X1917524Y1190103D01*
X1917266Y1189949D01*
X1916749Y1189183D01*
X1916388Y1188838D01*
X1915871Y1188608D01*
X1915406Y1188531D01*
Y1190141D01*
G01X1917098Y1652965D02*
X1920198D01*
Y1653731D01*
X1920043Y1654038D01*
X1919836Y1654268D01*
X1919526Y1654460D01*
X1919165Y1654613D01*
X1918648Y1654651D01*
X1918131Y1654613D01*
X1917770Y1654460D01*
X1917460Y1654268D01*
X1917253Y1654038D01*
X1917098Y1653731D01*
Y1652965D01*
G01X1918751Y1657215D02*
X1918906Y1657368D01*
X1919165Y1657483D01*
X1919526Y1657560D01*
X1919836Y1657483D01*
X1920043Y1657330D01*
X1920198Y1657061D01*
Y1656026D01*
X1917098D01*
Y1657291D01*
X1917305Y1657560D01*
X1917615Y1657713D01*
X1917976Y1657790D01*
X1918338Y1657713D01*
X1918648Y1657483D01*
X1918751Y1657215D01*
Y1656026D01*
G01X1918390Y1659280D02*
X1918751Y1659548D01*
X1918958Y1659778D01*
X1919061Y1660085D01*
X1918958Y1660353D01*
X1918751Y1660545D01*
X1918441Y1660698D01*
X1918080Y1660736D01*
X1917770Y1660698D01*
X1917460Y1660545D01*
X1917201Y1660315D01*
X1917098Y1660046D01*
X1917201Y1659740D01*
X1917511Y1659471D01*
X1917976Y1659318D01*
X1918493Y1659280D01*
X1919165Y1659356D01*
X1919526Y1659471D01*
X1919888Y1659663D01*
X1920146Y1659931D01*
X1920198Y1660200D01*
X1920095Y1660468D01*
X1919836Y1660660D01*
G01X1916395Y592868D02*
Y602868D01*
G01X1923895D02*
X1928895D01*
G01X1916395D02*
X1918895D01*
G01X1926945Y592868D02*
X1925845D01*
G01X1916945D02*
X1916395D01*
G01X1929593Y609580D02*
X1932693Y611190D01*
G01Y609580D02*
X1929593Y611190D01*
G01X1930885Y612757D02*
X1931246Y613025D01*
X1931453Y613255D01*
X1931556Y613562D01*
X1931453Y613830D01*
X1931246Y614022D01*
X1930936Y614175D01*
X1930575Y614213D01*
X1930265Y614175D01*
X1929955Y614022D01*
X1929696Y613792D01*
X1929593Y613523D01*
X1929696Y613217D01*
X1930006Y612948D01*
X1930471Y612795D01*
X1930988Y612757D01*
X1931660Y612833D01*
X1932021Y612948D01*
X1932383Y613140D01*
X1932641Y613408D01*
X1932693Y613677D01*
X1932590Y613945D01*
X1932331Y614137D01*
G01X1917500Y718345D02*
X1920600Y719955D01*
G01Y718345D02*
X1917500Y719955D01*
G01Y722710D02*
X1920600D01*
X1918378Y721292D01*
Y723208D01*
G01X1917965Y724507D02*
X1917707Y724737D01*
X1917552Y725005D01*
X1917500Y725350D01*
X1917603Y725695D01*
X1917810Y725963D01*
X1918172Y726155D01*
X1918585Y726193D01*
X1918998Y726117D01*
X1919257Y725925D01*
X1919463Y725657D01*
X1919515Y725388D01*
X1919463Y725120D01*
X1919257Y724775D01*
X1920600Y724890D01*
Y725925D01*
G01X1917500Y832845D02*
X1920600Y834455D01*
G01Y832845D02*
X1917500Y834455D01*
G01X1918120Y835907D02*
X1917758Y836137D01*
X1917552Y836443D01*
X1917500Y836788D01*
X1917552Y837095D01*
X1917810Y837402D01*
X1918120Y837593D01*
X1918430Y837632D01*
X1918792Y837555D01*
X1919050Y837287D01*
X1919153Y837018D01*
Y836673D01*
G01Y837018D02*
X1919308Y837248D01*
X1919567Y837440D01*
X1919877Y837517D01*
X1920187Y837440D01*
X1920445Y837248D01*
X1920600Y836903D01*
X1920548Y836558D01*
X1920342Y836213D01*
G01X1917500Y839773D02*
X1918172Y839850D01*
X1918740Y839965D01*
X1919257Y840118D01*
X1919825Y840310D01*
X1920600Y840617D01*
Y839083D01*
G01X1916395Y1195068D02*
Y1205068D01*
G01D02*
X1916945D01*
G01X1925845D02*
X1926945D01*
G01X1918895Y1195068D02*
X1916395D01*
G01X1928895D02*
X1923895D01*
G01X1917087Y1368332D02*
X1930200Y1333756D01*
G01D02*
X1943313Y1368332D01*
G01D02*
X1917087D01*
G01X1929695Y1699012D02*
X1916582Y1664436D01*
G01D02*
X1942808D01*
G01D02*
X1929695Y1699012D01*
G01X1937395Y-19152D02*
Y-9152D01*
G01X1937945Y-19152D02*
X1937395D01*
G01X1947945D02*
X1946845D01*
G01X1937395Y-9152D02*
X1939895D01*
G01X1944895D02*
X1949895D01*
G01X1938593Y568959D02*
X1941693Y570569D01*
G01Y568959D02*
X1938593Y570569D01*
G01X1939213Y572021D02*
X1938851Y572251D01*
X1938645Y572557D01*
X1938593Y572902D01*
X1938645Y573209D01*
X1938903Y573516D01*
X1939213Y573707D01*
X1939523Y573746D01*
X1939885Y573669D01*
X1940143Y573401D01*
X1940246Y573132D01*
Y572787D01*
G01Y573132D02*
X1940401Y573362D01*
X1940660Y573554D01*
X1940970Y573631D01*
X1941280Y573554D01*
X1941538Y573362D01*
X1941693Y573017D01*
X1941641Y572672D01*
X1941435Y572327D01*
G01X1941176Y575236D02*
X1941486Y575466D01*
X1941641Y575734D01*
X1941693Y576041D01*
X1941590Y576424D01*
X1941331Y576692D01*
X1941021Y576769D01*
X1940711Y576731D01*
X1940453Y576577D01*
X1939936Y575811D01*
X1939575Y575466D01*
X1939058Y575236D01*
X1938593Y575159D01*
Y576769D01*
G01X1937395Y583048D02*
Y593048D01*
G01X1939895Y583048D02*
X1937395D01*
G01X1949895D02*
X1944895D01*
G01X1937395Y593048D02*
X1937945D01*
G01X1946845D02*
X1947945D01*
G01X1933895Y602868D02*
X1936395D01*
G01D02*
Y592868D01*
G01D02*
X1935845D01*
G01Y1205068D02*
X1936395D01*
G01D02*
Y1195068D01*
G01D02*
X1933895D01*
G01X1939198Y1372025D02*
X1942298D01*
Y1372791D01*
X1942143Y1373098D01*
X1941936Y1373328D01*
X1941626Y1373520D01*
X1941265Y1373673D01*
X1940748Y1373711D01*
X1940231Y1373673D01*
X1939870Y1373520D01*
X1939560Y1373328D01*
X1939353Y1373098D01*
X1939198Y1372791D01*
Y1372025D01*
G01X1940851Y1376275D02*
X1941006Y1376428D01*
X1941265Y1376543D01*
X1941626Y1376620D01*
X1941936Y1376543D01*
X1942143Y1376390D01*
X1942298Y1376121D01*
Y1375086D01*
X1939198D01*
Y1376351D01*
X1939405Y1376620D01*
X1939715Y1376773D01*
X1940076Y1376850D01*
X1940438Y1376773D01*
X1940748Y1376543D01*
X1940851Y1376275D01*
Y1375086D01*
G01X1939198Y1379068D02*
X1942298D01*
X1941678Y1378608D01*
G01X1939198D02*
Y1379528D01*
G01Y1382628D02*
X1942298D01*
X1940076Y1381210D01*
Y1383126D01*
G01X1957395Y-9152D02*
Y-19152D01*
G01D02*
X1956845D01*
G01X1954320Y-3755D02*
X1957420Y-2145D01*
G01Y-3755D02*
X1954320Y-2145D01*
G01X1954940Y-693D02*
X1954578Y-463D01*
X1954372Y-157D01*
X1954320Y188D01*
X1954372Y495D01*
X1954630Y802D01*
X1954940Y993D01*
X1955250Y1032D01*
X1955612Y955D01*
X1955870Y687D01*
X1955973Y418D01*
Y73D01*
G01Y418D02*
X1956128Y648D01*
X1956387Y840D01*
X1956697Y917D01*
X1957007Y840D01*
X1957265Y648D01*
X1957420Y303D01*
X1957368Y-42D01*
X1957162Y-387D01*
G01X1957420Y3250D02*
X1957317Y2943D01*
X1957058Y2713D01*
X1956748Y2560D01*
X1956335Y2445D01*
X1955870Y2407D01*
X1955405Y2445D01*
X1954992Y2560D01*
X1954682Y2713D01*
X1954423Y2943D01*
X1954320Y3250D01*
X1954423Y3557D01*
X1954682Y3787D01*
X1954992Y3940D01*
X1955405Y4055D01*
X1955870Y4093D01*
X1956335Y4055D01*
X1956748Y3940D01*
X1957058Y3787D01*
X1957317Y3557D01*
X1957420Y3250D01*
G01X1954895Y-9152D02*
X1957395D01*
G01Y593048D02*
Y583048D01*
G01D02*
X1954895D01*
G01X1958362Y603010D02*
X1960862D01*
G01X1958362Y593010D02*
Y603010D01*
G01X1958912Y593010D02*
X1958362D01*
G01X1956845Y593048D02*
X1957395D01*
G01X1958830Y1182061D02*
X1961930Y1183671D01*
G01Y1182061D02*
X1958830Y1183671D01*
G01X1961413Y1185238D02*
X1961723Y1185468D01*
X1961878Y1185736D01*
X1961930Y1186043D01*
X1961827Y1186426D01*
X1961568Y1186694D01*
X1961258Y1186771D01*
X1960948Y1186733D01*
X1960690Y1186579D01*
X1960173Y1185813D01*
X1959812Y1185468D01*
X1959295Y1185238D01*
X1958830Y1185161D01*
Y1186771D01*
G01X1960122Y1188338D02*
X1960483Y1188606D01*
X1960690Y1188836D01*
X1960793Y1189143D01*
X1960690Y1189411D01*
X1960483Y1189603D01*
X1960173Y1189756D01*
X1959812Y1189794D01*
X1959502Y1189756D01*
X1959192Y1189603D01*
X1958933Y1189373D01*
X1958830Y1189104D01*
X1958933Y1188798D01*
X1959243Y1188529D01*
X1959708Y1188376D01*
X1960225Y1188338D01*
X1960897Y1188414D01*
X1961258Y1188529D01*
X1961620Y1188721D01*
X1961878Y1188989D01*
X1961930Y1189258D01*
X1961827Y1189526D01*
X1961568Y1189718D01*
G01X1958362Y1195210D02*
Y1205210D01*
G01D02*
X1958912D01*
G01X1960862Y1195210D02*
X1958362D01*
G01X1959584Y1368390D02*
X1972697Y1333814D01*
G01X1985810Y1368390D02*
X1959584D01*
G01X1960538Y1650205D02*
X1963638D01*
Y1650971D01*
X1963483Y1651278D01*
X1963276Y1651508D01*
X1962966Y1651700D01*
X1962605Y1651853D01*
X1962088Y1651891D01*
X1961571Y1651853D01*
X1961210Y1651700D01*
X1960900Y1651508D01*
X1960693Y1651278D01*
X1960538Y1650971D01*
Y1650205D01*
G01X1962191Y1654455D02*
X1962346Y1654608D01*
X1962605Y1654723D01*
X1962966Y1654800D01*
X1963276Y1654723D01*
X1963483Y1654570D01*
X1963638Y1654301D01*
Y1653266D01*
X1960538D01*
Y1654531D01*
X1960745Y1654800D01*
X1961055Y1654953D01*
X1961416Y1655030D01*
X1961778Y1654953D01*
X1962088Y1654723D01*
X1962191Y1654455D01*
Y1653266D01*
G01X1960538Y1657248D02*
X1963638D01*
X1963018Y1656788D01*
G01X1960538D02*
Y1657708D01*
G01X1961158Y1659505D02*
X1960796Y1659735D01*
X1960590Y1660041D01*
X1960538Y1660386D01*
X1960590Y1660693D01*
X1960848Y1661000D01*
X1961158Y1661191D01*
X1961468Y1661230D01*
X1961830Y1661153D01*
X1962088Y1660885D01*
X1962191Y1660616D01*
Y1660271D01*
G01Y1660616D02*
X1962346Y1660846D01*
X1962605Y1661038D01*
X1962915Y1661115D01*
X1963225Y1661038D01*
X1963483Y1660846D01*
X1963638Y1660501D01*
X1963586Y1660156D01*
X1963380Y1659811D01*
G01X1971555Y1698922D02*
X1958442Y1664346D01*
G01D02*
X1984668D01*
G01X1979482Y-19180D02*
Y-9180D01*
G01X1980032Y-19180D02*
X1979482D01*
G01Y-9180D02*
X1981982D01*
G01X1979650Y568661D02*
X1982750Y570271D01*
G01Y568661D02*
X1979650Y570271D01*
G01X1982233Y571838D02*
X1982543Y572068D01*
X1982698Y572336D01*
X1982750Y572643D01*
X1982647Y573026D01*
X1982388Y573294D01*
X1982078Y573371D01*
X1981768Y573333D01*
X1981510Y573179D01*
X1980993Y572413D01*
X1980632Y572068D01*
X1980115Y571838D01*
X1979650Y571761D01*
Y573371D01*
G01X1980012Y575014D02*
X1979753Y575283D01*
X1979650Y575589D01*
X1979753Y575896D01*
X1980063Y576164D01*
X1980528Y576356D01*
X1980993Y576433D01*
X1981562D01*
X1982027Y576356D01*
X1982440Y576164D01*
X1982647Y575934D01*
X1982750Y575666D01*
X1982647Y575359D01*
X1982440Y575129D01*
X1982130Y574976D01*
X1981717Y574899D01*
X1981355Y574976D01*
X1980993Y575168D01*
X1980787Y575398D01*
X1980735Y575666D01*
X1980838Y575973D01*
X1981097Y576203D01*
X1981562Y576433D01*
G01X1979482Y583020D02*
Y593020D01*
G01X1981982Y583020D02*
X1979482D01*
G01Y593020D02*
X1980032D01*
G01X1965862Y603010D02*
X1970862D01*
G01X1975862D02*
X1978362D01*
G01D02*
Y593010D01*
G01X1968912D02*
X1967812D01*
G01X1978362D02*
X1977812D01*
G01X1972207Y609110D02*
X1975307Y610720D01*
G01Y609110D02*
X1972207Y610720D01*
G01X1974790Y612287D02*
X1975100Y612517D01*
X1975255Y612785D01*
X1975307Y613092D01*
X1975204Y613475D01*
X1974945Y613743D01*
X1974635Y613820D01*
X1974325Y613782D01*
X1974067Y613628D01*
X1973550Y612862D01*
X1973189Y612517D01*
X1972672Y612287D01*
X1972207Y612210D01*
Y613820D01*
G01Y616115D02*
X1972259Y616383D01*
X1972414Y616690D01*
X1972672Y616882D01*
X1973034Y616958D01*
X1973395Y616882D01*
X1973705Y616652D01*
X1973860Y616307D01*
Y615923D01*
X1973964Y615693D01*
X1974222Y615502D01*
X1974584Y615425D01*
X1974945Y615540D01*
X1975204Y615808D01*
X1975307Y616115D01*
X1975204Y616422D01*
X1974945Y616690D01*
X1974584Y616805D01*
X1974222Y616728D01*
X1973964Y616537D01*
X1973860Y616307D01*
Y615923D01*
X1973705Y615578D01*
X1973395Y615348D01*
X1973034Y615272D01*
X1972672Y615348D01*
X1972414Y615540D01*
X1972259Y615847D01*
X1972207Y616115D01*
G01X1977812Y1205210D02*
X1978362D01*
G01D02*
Y1195210D01*
G01X1967812Y1205210D02*
X1968912D01*
G01X1978362Y1195210D02*
X1975862D01*
G01X1970862D02*
X1965862D01*
G01X1972697Y1333814D02*
X1983826Y1363159D01*
G01X1981478Y1372625D02*
X1984578D01*
Y1373391D01*
X1984423Y1373698D01*
X1984216Y1373928D01*
X1983906Y1374120D01*
X1983545Y1374273D01*
X1983028Y1374311D01*
X1982511Y1374273D01*
X1982150Y1374120D01*
X1981840Y1373928D01*
X1981633Y1373698D01*
X1981478Y1373391D01*
Y1372625D01*
G01X1983131Y1376875D02*
X1983286Y1377028D01*
X1983545Y1377143D01*
X1983906Y1377220D01*
X1984216Y1377143D01*
X1984423Y1376990D01*
X1984578Y1376721D01*
Y1375686D01*
X1981478D01*
Y1376951D01*
X1981685Y1377220D01*
X1981995Y1377373D01*
X1982356Y1377450D01*
X1982718Y1377373D01*
X1983028Y1377143D01*
X1983131Y1376875D01*
Y1375686D01*
G01X1981943Y1378825D02*
X1981685Y1379055D01*
X1981530Y1379323D01*
X1981478Y1379668D01*
X1981581Y1380013D01*
X1981788Y1380281D01*
X1982150Y1380473D01*
X1982563Y1380511D01*
X1982976Y1380435D01*
X1983235Y1380243D01*
X1983441Y1379975D01*
X1983493Y1379706D01*
X1983441Y1379438D01*
X1983235Y1379093D01*
X1984578Y1379208D01*
Y1380243D01*
G01X1984668Y1664346D02*
X1971555Y1698922D01*
G01X1990032Y-19180D02*
X1988932D01*
G01X1995670Y-3005D02*
X1998770Y-1395D01*
G01Y-3005D02*
X1995670Y-1395D01*
G01X1996290Y57D02*
X1995928Y287D01*
X1995722Y593D01*
X1995670Y938D01*
X1995722Y1245D01*
X1995980Y1552D01*
X1996290Y1743D01*
X1996600Y1782D01*
X1996962Y1705D01*
X1997220Y1437D01*
X1997323Y1168D01*
Y823D01*
G01Y1168D02*
X1997478Y1398D01*
X1997737Y1590D01*
X1998047Y1667D01*
X1998357Y1590D01*
X1998615Y1398D01*
X1998770Y1053D01*
X1998718Y708D01*
X1998512Y363D01*
G01X1995670Y4000D02*
X1998770D01*
X1998150Y3540D01*
G01X1995670D02*
Y4460D01*
G01X1986982Y-9180D02*
X1991982D01*
G01X1996982D02*
X1999482D01*
G01X1991982Y583020D02*
X1986982D01*
G01X1999482D02*
X1996982D01*
G01X1988932Y593020D02*
X1990032D01*
G01X1985232Y1366865D02*
X1985810Y1368390D01*
G01X1999482Y-9180D02*
Y-19180D01*
G01D02*
X1998932D01*
G01X1999482Y593020D02*
Y583020D01*
G01X1998932Y593020D02*
X1999482D01*
G01X2000452Y603020D02*
X2002952D01*
G01X2007952D02*
X2012952D01*
G01X2000452Y593020D02*
Y603020D01*
G01X2001002Y593020D02*
X2000452D01*
G01X2011002D02*
X2009902D01*
G01X2003530Y1181885D02*
X2006630Y1183495D01*
G01Y1181885D02*
X2003530Y1183495D01*
G01X2006113Y1185062D02*
X2006423Y1185292D01*
X2006578Y1185560D01*
X2006630Y1185867D01*
X2006527Y1186250D01*
X2006268Y1186518D01*
X2005958Y1186595D01*
X2005648Y1186557D01*
X2005390Y1186403D01*
X2004873Y1185637D01*
X2004512Y1185292D01*
X2003995Y1185062D01*
X2003530Y1184985D01*
Y1186595D01*
G01Y1188813D02*
X2004202Y1188890D01*
X2004770Y1189005D01*
X2005287Y1189158D01*
X2005855Y1189350D01*
X2006630Y1189657D01*
Y1188123D01*
G01X2009902Y1205220D02*
X2011002D01*
G01X2000452Y1195220D02*
Y1205220D01*
G01D02*
X2001002D01*
G01X2012952Y1195220D02*
X2007952D01*
G01X2002952D02*
X2000452D01*
G01X2022002Y-19000D02*
X2021452D01*
G01D02*
Y-9000D01*
G01D02*
X2023952D01*
G01X2028952D02*
X2033952D01*
G01X2022033Y569089D02*
X2025133Y570699D01*
G01Y569089D02*
X2022033Y570699D01*
G01X2024616Y572266D02*
X2024926Y572496D01*
X2025081Y572764D01*
X2025133Y573071D01*
X2025030Y573454D01*
X2024771Y573722D01*
X2024461Y573799D01*
X2024151Y573761D01*
X2023893Y573607D01*
X2023376Y572841D01*
X2023015Y572496D01*
X2022498Y572266D01*
X2022033Y572189D01*
Y573799D01*
G01X2022653Y575251D02*
X2022291Y575481D01*
X2022085Y575787D01*
X2022033Y576132D01*
X2022085Y576439D01*
X2022343Y576746D01*
X2022653Y576937D01*
X2022963Y576976D01*
X2023325Y576899D01*
X2023583Y576631D01*
X2023686Y576362D01*
Y576017D01*
G01Y576362D02*
X2023841Y576592D01*
X2024100Y576784D01*
X2024410Y576861D01*
X2024720Y576784D01*
X2024978Y576592D01*
X2025133Y576247D01*
X2025081Y575902D01*
X2024875Y575557D01*
G01X2033952Y583200D02*
X2028952D01*
G01X2023952D02*
X2021452D01*
G01D02*
Y593200D01*
G01D02*
X2022002D01*
G01X2017952Y603020D02*
X2020452D01*
G01D02*
Y593020D01*
G01D02*
X2019902D01*
G01X2015634Y609338D02*
X2018734Y610948D01*
G01Y609338D02*
X2015634Y610948D01*
G01X2018217Y612515D02*
X2018527Y612745D01*
X2018682Y613013D01*
X2018734Y613320D01*
X2018631Y613703D01*
X2018372Y613971D01*
X2018062Y614048D01*
X2017752Y614010D01*
X2017494Y613856D01*
X2016977Y613090D01*
X2016616Y612745D01*
X2016099Y612515D01*
X2015634Y612438D01*
Y614048D01*
G01X2016099Y615500D02*
X2015841Y615730D01*
X2015686Y615998D01*
X2015634Y616343D01*
X2015737Y616688D01*
X2015944Y616956D01*
X2016306Y617148D01*
X2016719Y617186D01*
X2017132Y617110D01*
X2017391Y616918D01*
X2017597Y616650D01*
X2017649Y616381D01*
X2017597Y616113D01*
X2017391Y615768D01*
X2018734Y615883D01*
Y616918D01*
G01X2019902Y1205220D02*
X2020452D01*
G01D02*
Y1195220D01*
G01D02*
X2017952D01*
G01X2032002Y-19000D02*
X2030902D01*
G01X2041452Y-9000D02*
Y-19000D01*
G01D02*
X2040902D01*
G01X2037690Y-3335D02*
X2040790Y-1725D01*
G01Y-3335D02*
X2037690Y-1725D01*
G01Y570D02*
X2040790D01*
X2040170Y110D01*
G01X2037690D02*
Y1030D01*
G01Y3593D02*
X2038362Y3670D01*
X2038930Y3785D01*
X2039447Y3938D01*
X2040015Y4130D01*
X2040790Y4437D01*
Y2903D01*
G01X2038952Y-9000D02*
X2041452D01*
G01Y583200D02*
X2038952D01*
G01X2041452Y593200D02*
Y583200D01*
G01X2030902Y593200D02*
X2032002D01*
G01X2040902D02*
X2041452D01*
G01X2042419Y603162D02*
X2044919D01*
G01X2042419Y593162D02*
Y603162D01*
G01X2042969Y593162D02*
X2042419D01*
G01X2045539Y1181955D02*
X2048639Y1183565D01*
G01Y1181955D02*
X2045539Y1183565D01*
G01Y1185860D02*
X2048639D01*
X2048019Y1185400D01*
G01X2045539D02*
Y1186320D01*
G01Y1188960D02*
X2048639D01*
X2048019Y1188500D01*
G01X2045539D02*
Y1189420D01*
G01X2042419Y1195362D02*
Y1205362D01*
G01D02*
X2042969D01*
G01X2044919Y1195362D02*
X2042419D01*
G01X2049919Y603162D02*
X2054919D01*
G01X2059919D02*
X2062419D01*
G01D02*
Y593162D01*
G01X2052969D02*
X2051869D01*
G01X2062419D02*
X2061869D01*
G01X2056461Y609307D02*
X2059561Y610917D01*
G01Y609307D02*
X2056461Y610917D01*
G01X2056926Y612369D02*
X2056668Y612599D01*
X2056513Y612867D01*
X2056461Y613212D01*
X2056564Y613557D01*
X2056771Y613825D01*
X2057133Y614017D01*
X2057546Y614055D01*
X2057959Y613979D01*
X2058218Y613787D01*
X2058424Y613519D01*
X2058476Y613250D01*
X2058424Y612982D01*
X2058218Y612637D01*
X2059561Y612752D01*
Y613787D01*
G01X2051869Y1205362D02*
X2052969D01*
G01X2061869D02*
X2062419D01*
G01D02*
Y1195362D01*
G01X2054919D02*
X2049919D01*
G01X2062419D02*
X2059919D01*
M02*
